FILE_TYPE = MACRO_DRAWING;
SET COLOR_WIRE YELLOW;
SET COLOR_PROP ORANGE;
SET COLOR_DOT WHITE;
SET COLOR_ARC YELLOW;
SET COLOR_BODY GREEN;
SET COLOR_NOTE PURPLE;
SET PROP_DISPLAY VALUE;
SET PAGE_NUMBER P181;
FORCEADD UNIVERSAL_POWER..1
(3800 2925);
FORCEPROP 3 LASTPIN (3800 2875) SIG_NAME P1V05_PCH_PLL_AUX\g
J 0
(3810 2885);
DISPLAY 0.659574 (3810 2885);
PAINT MONO (3810 2885);
DISPLAY INVISIBLE (3810 2885);
FORCEPROP 1 LAST HDL_POWER P1V05_PCH_PLL_AUX
J 1
(3800 2975);
DISPLAY 0.872340 (3800 2975);
PAINT GREEN (3800 2975);
FORCEPROP 1 LAST PATH I103
J 0
(3850 2950);
DISPLAY 0.872340 (3850 2950);
PAINT AQUA (3850 2950);
DISPLAY INVISIBLE (3850 2950);
FORCEPROP 2 LAST CDS_LIB logical_power
J 0
(3800 2925);
PAINT MONO (3800 2925);
DISPLAY INVISIBLE (3800 2925);
FORCEADD Q_CAP..1
(3800 2650);
FORCEPROP 1 LAST PART_NUMBER CH6101MEB01
J 0
(3850 2500);
DISPLAY 0.638298 (3850 2500);
DISPLAY INVISIBLE (3850 2500);
FORCEPROP 1 LAST VALUE 10UF
J 0
(3850 2700);
DISPLAY 0.638298 (3850 2700);
FORCEPROP 1 LAST VOLTAGE 6.3V
J 0
(3850 2650);
DISPLAY 0.638298 (3850 2650);
FORCEPROP 1 LAST MATERIAL X6S
J 0
(3850 2550);
DISPLAY 0.638298 (3850 2550);
FORCEPROP 1 LAST PACK_TYPE C0402
J 0
(3850 2450);
DISPLAY 0.638298 (3850 2450);
FORCEPROP 1 LAST TOLERANCE 20%
J 0
(3850 2600);
DISPLAY 0.638298 (3850 2600);
FORCEPROP 1 LAST $LOCATION C1262
J 0
(3850 2750);
DISPLAY 0.638298 (3850 2750);
FORCEPROP 1 LASTPIN (3800 2750) $PN 1
J 0
(3810 2730);
DISPLAY 0.787234 (3810 2730);
FORCEPROP 1 LASTPIN (3800 2550) $PN 2
J 0
(3810 2530);
DISPLAY 0.787234 (3810 2530);
FORCEPROP 1 LAST PATH I104
J 0
(3850 2800);
DISPLAY 0.978723 (3850 2800);
PAINT WHITE (3850 2800);
DISPLAY INVISIBLE (3850 2800);
FORCEPROP 2 LAST CDS_LIB pure_quanta
J 0
(3800 2650);
PAINT MONO (3800 2650);
DISPLAY INVISIBLE (3800 2650);
FORCEPROP 2 LAST CDS_LOCATION C1262
J 0
(3850 2850);
DISPLAY 1.021277 (3850 2850);
DISPLAY INVISIBLE (3850 2850);
FORCEPROP 2 LAST $SEC 1
J 0
(3850 2850);
DISPLAY 0.680851 (3850 2850);
PAINT MONO (3850 2850);
DISPLAY INVISIBLE (3850 2850);
FORCEPROP 2 LAST CDS_SEC 1
J 0
(3850 2850);
DISPLAY 1.021277 (3850 2850);
DISPLAY INVISIBLE (3850 2850);
FORCEADD UNIVERSAL_GND..1
(3275 2300);
FORCEPROP 3 LASTPIN (3275 2350) SIG_NAME GND\g
J 0
(3285 2360);
DISPLAY 0.659574 (3285 2360);
PAINT MONO (3285 2360);
DISPLAY INVISIBLE (3285 2360);
FORCEPROP 2 LAST ROOM IO_SLOT
J 1
(3050 2375);
DISPLAY 0.744681 (3050 2375);
DISPLAY INVISIBLE (3050 2375);
FORCEPROP 1 LAST PATH I106
J 0
(3350 2300);
DISPLAY 0.872340 (3350 2300);
PAINT AQUA (3350 2300);
DISPLAY INVISIBLE (3350 2300);
FORCEPROP 1 LAST HDL_POWER GND
J 1
(3300 2225);
DISPLAY 0.872340 (3300 2225);
PAINT GREEN (3300 2225);
DISPLAY INVISIBLE (3300 2225);
FORCEPROP 2 LAST CDS_LIB logical_power
J 0
(3275 2300);
PAINT MONO (3275 2300);
DISPLAY INVISIBLE (3275 2300);
FORCEADD UNIVERSAL_POWER..1
(2375 2925);
FORCEPROP 3 LASTPIN (2375 2875) SIG_NAME P1V05_PCH_PLL_AUX\g
J 0
(2385 2885);
DISPLAY 0.659574 (2385 2885);
PAINT MONO (2385 2885);
DISPLAY INVISIBLE (2385 2885);
FORCEPROP 1 LAST HDL_POWER P1V05_PCH_PLL_AUX
J 1
(2375 2975);
DISPLAY 0.872340 (2375 2975);
PAINT GREEN (2375 2975);
FORCEPROP 1 LAST PATH I108
J 0
(2425 2950);
DISPLAY 0.872340 (2425 2950);
PAINT AQUA (2425 2950);
DISPLAY INVISIBLE (2425 2950);
FORCEPROP 2 LAST CDS_LIB logical_power
J 0
(2375 2925);
DISPLAY INVISIBLE (2375 2925);
FORCEADD UNIVERSAL_POWER..1
(-850 4100);
FORCEPROP 3 LASTPIN (-850 4050) SIG_NAME P1V05_PCH_AUX\g
J 0
(-840 4060);
DISPLAY 0.659574 (-840 4060);
PAINT MONO (-840 4060);
DISPLAY INVISIBLE (-840 4060);
FORCEPROP 1 LAST HDL_POWER P1V05_PCH_AUX
J 1
(-850 4150);
DISPLAY 0.872340 (-850 4150);
PAINT GREEN (-850 4150);
FORCEPROP 1 LAST PATH I11
J 0
(-800 4125);
DISPLAY 0.872340 (-800 4125);
PAINT AQUA (-800 4125);
DISPLAY INVISIBLE (-800 4125);
FORCEPROP 2 LAST CDS_LIB logical_power
J 0
(-850 4100);
PAINT MONO (-850 4100);
DISPLAY INVISIBLE (-850 4100);
FORCEADD Q_CAP..1
(2375 2650);
FORCEPROP 1 LAST PART_NUMBER CH6101ME900
J 0
(2425 2500);
DISPLAY 0.638298 (2425 2500);
DISPLAY INVISIBLE (2425 2500);
FORCEPROP 1 LAST MATERIAL X6S
J 0
(2425 2550);
DISPLAY 0.638298 (2425 2550);
FORCEPROP 1 LAST VOLTAGE 6.3V
J 0
(2425 2650);
DISPLAY 0.638298 (2425 2650);
FORCEPROP 1 LAST TOLERANCE 20%
J 0
(2425 2600);
DISPLAY 0.638298 (2425 2600);
FORCEPROP 1 LAST VALUE 10UF
J 0
(2425 2700);
DISPLAY 0.638298 (2425 2700);
FORCEPROP 1 LAST PACK_TYPE C0603
J 0
(2425 2450);
DISPLAY 0.638298 (2425 2450);
FORCEPROP 1 LAST $LOCATION C1251
J 0
(2425 2750);
DISPLAY 0.638298 (2425 2750);
FORCEPROP 1 LASTPIN (2375 2750) $PN 1
J 0
(2385 2730);
DISPLAY 0.787234 (2385 2730);
FORCEPROP 1 LASTPIN (2375 2550) $PN 2
J 0
(2385 2530);
DISPLAY 0.787234 (2385 2530);
FORCEPROP 1 LAST PATH I110
J 0
(2425 2800);
DISPLAY 0.978723 (2425 2800);
PAINT WHITE (2425 2800);
DISPLAY INVISIBLE (2425 2800);
FORCEPROP 2 LAST CDS_LIB pure_quanta
J 0
(2375 2650);
PAINT MONO (2375 2650);
DISPLAY INVISIBLE (2375 2650);
FORCEPROP 2 LAST CDS_LOCATION C1251
J 0
(2425 2850);
DISPLAY 1.021277 (2425 2850);
DISPLAY INVISIBLE (2425 2850);
FORCEPROP 2 LAST $SEC 1
J 0
(2425 2850);
DISPLAY 0.680851 (2425 2850);
PAINT MONO (2425 2850);
DISPLAY INVISIBLE (2425 2850);
FORCEPROP 2 LAST CDS_SEC 1
J 0
(2425 2850);
DISPLAY 1.021277 (2425 2850);
DISPLAY INVISIBLE (2425 2850);
FORCEADD Q_CAP..1
(2825 2650);
FORCEPROP 1 LAST PART_NUMBER CH6101ME900
J 0
(2875 2500);
DISPLAY 0.638298 (2875 2500);
DISPLAY INVISIBLE (2875 2500);
FORCEPROP 1 LAST VOLTAGE 6.3V
J 0
(2875 2650);
DISPLAY 0.638298 (2875 2650);
FORCEPROP 1 LAST TOLERANCE 20%
J 0
(2875 2600);
DISPLAY 0.638298 (2875 2600);
FORCEPROP 1 LAST VALUE 10UF
J 0
(2875 2700);
DISPLAY 0.638298 (2875 2700);
FORCEPROP 1 LAST MATERIAL X6S
J 0
(2875 2550);
DISPLAY 0.638298 (2875 2550);
FORCEPROP 1 LAST PACK_TYPE C0603
J 0
(2875 2450);
DISPLAY 0.638298 (2875 2450);
FORCEPROP 1 LAST $LOCATION C1254
J 0
(2875 2750);
DISPLAY 0.638298 (2875 2750);
FORCEPROP 1 LASTPIN (2825 2750) $PN 1
J 0
(2835 2730);
DISPLAY 0.787234 (2835 2730);
FORCEPROP 1 LASTPIN (2825 2550) $PN 2
J 0
(2835 2530);
DISPLAY 0.787234 (2835 2530);
FORCEPROP 1 LAST PATH I111
J 0
(2875 2800);
DISPLAY 0.978723 (2875 2800);
PAINT WHITE (2875 2800);
DISPLAY INVISIBLE (2875 2800);
FORCEPROP 2 LAST CDS_LIB pure_quanta
J 0
(2825 2650);
PAINT MONO (2825 2650);
DISPLAY INVISIBLE (2825 2650);
FORCEPROP 2 LAST CDS_LOCATION C1254
J 0
(2875 2850);
DISPLAY 1.021277 (2875 2850);
DISPLAY INVISIBLE (2875 2850);
FORCEPROP 2 LAST $SEC 1
J 0
(2875 2850);
DISPLAY 0.680851 (2875 2850);
PAINT MONO (2875 2850);
DISPLAY INVISIBLE (2875 2850);
FORCEPROP 2 LAST CDS_SEC 1
J 0
(2875 2850);
DISPLAY 1.021277 (2875 2850);
DISPLAY INVISIBLE (2875 2850);
FORCEADD UNIVERSAL_GND..1
(3800 2300);
FORCEPROP 3 LASTPIN (3800 2350) SIG_NAME GND\g
J 0
(3810 2360);
DISPLAY 0.659574 (3810 2360);
PAINT MONO (3810 2360);
DISPLAY INVISIBLE (3810 2360);
FORCEPROP 2 LAST ROOM IO_SLOT
J 1
(3575 2375);
DISPLAY 0.744681 (3575 2375);
DISPLAY INVISIBLE (3575 2375);
FORCEPROP 1 LAST PATH I113
J 0
(3875 2300);
DISPLAY 0.872340 (3875 2300);
PAINT AQUA (3875 2300);
DISPLAY INVISIBLE (3875 2300);
FORCEPROP 1 LAST HDL_POWER GND
J 1
(3825 2225);
DISPLAY 0.872340 (3825 2225);
PAINT GREEN (3825 2225);
DISPLAY INVISIBLE (3825 2225);
FORCEPROP 2 LAST CDS_LIB logical_power
J 0
(3800 2300);
PAINT MONO (3800 2300);
DISPLAY INVISIBLE (3800 2300);
FORCEADD UNIVERSAL_GND..1
(4700 2300);
FORCEPROP 3 LASTPIN (4700 2350) SIG_NAME GND\g
J 0
(4710 2360);
DISPLAY 0.659574 (4710 2360);
PAINT MONO (4710 2360);
DISPLAY INVISIBLE (4710 2360);
FORCEPROP 2 LAST ROOM IO_SLOT
J 1
(4475 2375);
DISPLAY 0.744681 (4475 2375);
DISPLAY INVISIBLE (4475 2375);
FORCEPROP 1 LAST PATH I114
J 0
(4775 2300);
DISPLAY 0.872340 (4775 2300);
PAINT AQUA (4775 2300);
DISPLAY INVISIBLE (4775 2300);
FORCEPROP 1 LAST HDL_POWER GND
J 1
(4725 2225);
DISPLAY 0.872340 (4725 2225);
PAINT GREEN (4725 2225);
DISPLAY INVISIBLE (4725 2225);
FORCEPROP 2 LAST CDS_LIB logical_power
J 0
(4700 2300);
PAINT MONO (4700 2300);
DISPLAY INVISIBLE (4700 2300);
FORCEADD UNIVERSAL_POWER..1
(4700 275);
FORCEPROP 3 LASTPIN (4700 225) SIG_NAME P1V8_PCH_PLL_AUX\g
J 0
(4710 235);
DISPLAY 0.659574 (4710 235);
PAINT MONO (4710 235);
DISPLAY INVISIBLE (4710 235);
FORCEPROP 1 LAST HDL_POWER P1V8_PCH_PLL_AUX
J 1
(4700 325);
DISPLAY 0.872340 (4700 325);
PAINT GREEN (4700 325);
FORCEPROP 1 LAST PATH I115
J 0
(4750 300);
DISPLAY 0.872340 (4750 300);
PAINT AQUA (4750 300);
DISPLAY INVISIBLE (4750 300);
FORCEPROP 2 LAST CDS_LIB logical_power
J 0
(4700 275);
DISPLAY INVISIBLE (4700 275);
FORCEADD UNIVERSAL_GND..1
(4700 -350);
FORCEPROP 3 LASTPIN (4700 -300) SIG_NAME GND\g
J 0
(4710 -290);
DISPLAY 0.659574 (4710 -290);
PAINT MONO (4710 -290);
DISPLAY INVISIBLE (4710 -290);
FORCEPROP 2 LAST ROOM IO_SLOT
J 1
(4475 -275);
DISPLAY 0.744681 (4475 -275);
DISPLAY INVISIBLE (4475 -275);
FORCEPROP 1 LAST PATH I117
J 0
(4775 -350);
DISPLAY 0.872340 (4775 -350);
PAINT AQUA (4775 -350);
DISPLAY INVISIBLE (4775 -350);
FORCEPROP 1 LAST HDL_POWER GND
J 1
(4725 -425);
DISPLAY 0.872340 (4725 -425);
PAINT GREEN (4725 -425);
DISPLAY INVISIBLE (4725 -425);
FORCEPROP 2 LAST CDS_LIB logical_power
J 0
(4700 -350);
PAINT MONO (4700 -350);
DISPLAY INVISIBLE (4700 -350);
FORCEADD UNIVERSAL_POWER..1
(3800 275);
FORCEPROP 3 LASTPIN (3800 225) SIG_NAME P1V8_PCH_PLL_AUX\g
J 0
(3810 235);
DISPLAY 0.659574 (3810 235);
PAINT MONO (3810 235);
DISPLAY INVISIBLE (3810 235);
FORCEPROP 1 LAST HDL_POWER P1V8_PCH_PLL_AUX
J 1
(3800 325);
DISPLAY 0.872340 (3800 325);
PAINT GREEN (3800 325);
FORCEPROP 1 LAST PATH I118
J 0
(3850 300);
DISPLAY 0.872340 (3850 300);
PAINT AQUA (3850 300);
DISPLAY INVISIBLE (3850 300);
FORCEPROP 2 LAST CDS_LIB logical_power
J 0
(3800 275);
PAINT MONO (3800 275);
DISPLAY INVISIBLE (3800 275);
FORCEADD Q_CAP..1
(3800 0);
FORCEPROP 1 LAST PART_NUMBER CH6101MEB01
J 0
(3850 -150);
DISPLAY 0.638298 (3850 -150);
DISPLAY INVISIBLE (3850 -150);
FORCEPROP 1 LAST PACK_TYPE C0402
J 0
(3850 -200);
DISPLAY 0.638298 (3850 -200);
FORCEPROP 1 LAST MATERIAL X6S
J 0
(3850 -100);
DISPLAY 0.638298 (3850 -100);
FORCEPROP 1 LAST TOLERANCE 20%
J 0
(3850 -50);
DISPLAY 0.638298 (3850 -50);
FORCEPROP 1 LAST VOLTAGE 6.3V
J 0
(3850 0);
DISPLAY 0.638298 (3850 0);
FORCEPROP 1 LAST VALUE 10UF
J 0
(3850 50);
DISPLAY 0.638298 (3850 50);
FORCEPROP 1 LAST $LOCATION C1263
J 0
(3850 100);
DISPLAY 0.638298 (3850 100);
FORCEPROP 1 LASTPIN (3800 100) $PN 1
J 0
(3810 80);
DISPLAY 0.787234 (3810 80);
FORCEPROP 1 LASTPIN (3800 -100) $PN 2
J 0
(3810 -120);
DISPLAY 0.787234 (3810 -120);
FORCEPROP 1 LAST PATH I119
J 0
(3850 150);
DISPLAY 0.978723 (3850 150);
PAINT WHITE (3850 150);
DISPLAY INVISIBLE (3850 150);
FORCEPROP 2 LAST CDS_LIB pure_quanta
J 0
(3800 0);
PAINT MONO (3800 0);
DISPLAY INVISIBLE (3800 0);
FORCEPROP 2 LAST CDS_LOCATION C1263
J 0
(3850 200);
DISPLAY 1.021277 (3850 200);
DISPLAY INVISIBLE (3850 200);
FORCEPROP 2 LAST $SEC 1
J 0
(3850 200);
DISPLAY 0.680851 (3850 200);
PAINT MONO (3850 200);
DISPLAY INVISIBLE (3850 200);
FORCEPROP 2 LAST CDS_SEC 1
J 0
(3850 200);
DISPLAY 1.021277 (3850 200);
DISPLAY INVISIBLE (3850 200);
FORCEADD Q_CAP..1
(-850 3825);
FORCEPROP 1 LAST PART_NUMBER CH6101MEB01
J 0
(-800 3675);
DISPLAY 0.638298 (-800 3675);
DISPLAY INVISIBLE (-800 3675);
FORCEPROP 1 LAST PACK_TYPE C0402
J 0
(-800 3625);
DISPLAY 0.638298 (-800 3625);
FORCEPROP 1 LAST MATERIAL X6S
J 0
(-800 3725);
DISPLAY 0.638298 (-800 3725);
FORCEPROP 1 LAST TOLERANCE 20%
J 0
(-800 3775);
DISPLAY 0.638298 (-800 3775);
FORCEPROP 1 LAST VOLTAGE 6.3V
J 0
(-800 3825);
DISPLAY 0.638298 (-800 3825);
FORCEPROP 1 LAST VALUE 10UF
J 0
(-800 3875);
DISPLAY 0.638298 (-800 3875);
FORCEPROP 1 LAST $LOCATION C1205
J 0
(-800 3925);
DISPLAY 0.638298 (-800 3925);
FORCEPROP 1 LASTPIN (-850 3925) $PN 1
J 0
(-840 3905);
DISPLAY 0.787234 (-840 3905);
FORCEPROP 1 LASTPIN (-850 3725) $PN 2
J 0
(-840 3705);
DISPLAY 0.787234 (-840 3705);
FORCEPROP 1 LAST PATH I12
J 0
(-800 3975);
DISPLAY 0.978723 (-800 3975);
PAINT WHITE (-800 3975);
DISPLAY INVISIBLE (-800 3975);
FORCEPROP 2 LAST CDS_LIB pure_quanta
J 0
(-850 3825);
PAINT MONO (-850 3825);
DISPLAY INVISIBLE (-850 3825);
FORCEPROP 2 LAST CDS_LOCATION C1205
J 0
(-800 4025);
DISPLAY 1.021277 (-800 4025);
DISPLAY INVISIBLE (-800 4025);
FORCEPROP 2 LAST $SEC 1
J 0
(-800 4025);
DISPLAY 0.680851 (-800 4025);
PAINT MONO (-800 4025);
DISPLAY INVISIBLE (-800 4025);
FORCEPROP 2 LAST CDS_SEC 1
J 0
(-800 4025);
DISPLAY 1.021277 (-800 4025);
DISPLAY INVISIBLE (-800 4025);
FORCEADD UNIVERSAL_GND..1
(3300 -350);
FORCEPROP 3 LASTPIN (3300 -300) SIG_NAME GND\g
J 0
(3310 -290);
DISPLAY 0.659574 (3310 -290);
PAINT MONO (3310 -290);
DISPLAY INVISIBLE (3310 -290);
FORCEPROP 2 LAST ROOM IO_SLOT
J 1
(3075 -275);
DISPLAY 0.744681 (3075 -275);
DISPLAY INVISIBLE (3075 -275);
FORCEPROP 1 LAST PATH I122
J 0
(3375 -350);
DISPLAY 0.872340 (3375 -350);
PAINT AQUA (3375 -350);
DISPLAY INVISIBLE (3375 -350);
FORCEPROP 1 LAST HDL_POWER GND
J 1
(3325 -425);
DISPLAY 0.872340 (3325 -425);
PAINT GREEN (3325 -425);
DISPLAY INVISIBLE (3325 -425);
FORCEPROP 2 LAST CDS_LIB logical_power
J 0
(3300 -350);
PAINT MONO (3300 -350);
DISPLAY INVISIBLE (3300 -350);
FORCEADD Q_CAP..1
(2850 0);
FORCEPROP 1 LAST PART_NUMBER CH6101ME900
J 0
(2900 -150);
DISPLAY 0.638298 (2900 -150);
DISPLAY INVISIBLE (2900 -150);
FORCEPROP 1 LAST VALUE 10UF
J 0
(2900 50);
DISPLAY 0.638298 (2900 50);
FORCEPROP 1 LAST MATERIAL X6S
J 0
(2900 -100);
DISPLAY 0.638298 (2900 -100);
FORCEPROP 1 LAST VOLTAGE 6.3V
J 0
(2900 0);
DISPLAY 0.638298 (2900 0);
FORCEPROP 1 LAST TOLERANCE 20%
J 0
(2900 -50);
DISPLAY 0.638298 (2900 -50);
FORCEPROP 1 LAST PACK_TYPE C0603
J 0
(2900 -200);
DISPLAY 0.638298 (2900 -200);
FORCEPROP 1 LAST $LOCATION C1255
J 0
(2900 100);
DISPLAY 0.638298 (2900 100);
FORCEPROP 1 LASTPIN (2850 100) $PN 1
J 0
(2860 80);
DISPLAY 0.787234 (2860 80);
FORCEPROP 1 LASTPIN (2850 -100) $PN 2
J 0
(2860 -120);
DISPLAY 0.787234 (2860 -120);
FORCEPROP 1 LAST PATH I123
J 0
(2900 150);
DISPLAY 0.978723 (2900 150);
PAINT WHITE (2900 150);
DISPLAY INVISIBLE (2900 150);
FORCEPROP 2 LAST CDS_LIB pure_quanta
J 0
(2850 0);
PAINT MONO (2850 0);
DISPLAY INVISIBLE (2850 0);
FORCEPROP 2 LAST CDS_LOCATION C1255
J 0
(2900 200);
DISPLAY 1.021277 (2900 200);
DISPLAY INVISIBLE (2900 200);
FORCEPROP 2 LAST $SEC 1
J 0
(2900 200);
DISPLAY 0.680851 (2900 200);
PAINT MONO (2900 200);
DISPLAY INVISIBLE (2900 200);
FORCEPROP 2 LAST CDS_SEC 1
J 0
(2900 200);
DISPLAY 1.021277 (2900 200);
DISPLAY INVISIBLE (2900 200);
FORCEADD UNIVERSAL_POWER..1
(2400 275);
FORCEPROP 3 LASTPIN (2400 225) SIG_NAME P1V8_PCH_PLL_AUX\g
J 0
(2410 235);
DISPLAY 0.659574 (2410 235);
PAINT MONO (2410 235);
DISPLAY INVISIBLE (2410 235);
FORCEPROP 1 LAST HDL_POWER P1V8_PCH_PLL_AUX
J 1
(2400 325);
DISPLAY 0.872340 (2400 325);
PAINT GREEN (2400 325);
FORCEPROP 1 LAST PATH I124
J 0
(2450 300);
DISPLAY 0.872340 (2450 300);
PAINT AQUA (2450 300);
DISPLAY INVISIBLE (2450 300);
FORCEPROP 2 LAST CDS_LIB logical_power
J 0
(2400 275);
DISPLAY INVISIBLE (2400 275);
FORCEADD Q_CAP..1
(2400 0);
FORCEPROP 1 LAST PART_NUMBER CH6101ME900
J 0
(2450 -150);
DISPLAY 0.638298 (2450 -150);
DISPLAY INVISIBLE (2450 -150);
FORCEPROP 1 LAST VOLTAGE 6.3V
J 0
(2450 0);
DISPLAY 0.638298 (2450 0);
FORCEPROP 1 LAST MATERIAL X6S
J 0
(2450 -100);
DISPLAY 0.638298 (2450 -100);
FORCEPROP 1 LAST TOLERANCE 20%
J 0
(2450 -50);
DISPLAY 0.638298 (2450 -50);
FORCEPROP 1 LAST PACK_TYPE C0603
J 0
(2450 -200);
DISPLAY 0.638298 (2450 -200);
FORCEPROP 1 LAST VALUE 10UF
J 0
(2450 50);
DISPLAY 0.638298 (2450 50);
FORCEPROP 1 LAST $LOCATION C1252
J 0
(2450 100);
DISPLAY 0.638298 (2450 100);
FORCEPROP 1 LASTPIN (2400 100) $PN 1
J 0
(2410 80);
DISPLAY 0.787234 (2410 80);
FORCEPROP 1 LASTPIN (2400 -100) $PN 2
J 0
(2410 -120);
DISPLAY 0.787234 (2410 -120);
FORCEPROP 1 LAST PATH I125
J 0
(2450 150);
DISPLAY 0.978723 (2450 150);
PAINT WHITE (2450 150);
DISPLAY INVISIBLE (2450 150);
FORCEPROP 2 LAST CDS_LIB pure_quanta
J 0
(2400 0);
PAINT MONO (2400 0);
DISPLAY INVISIBLE (2400 0);
FORCEPROP 2 LAST CDS_LOCATION C1252
J 0
(2450 200);
DISPLAY 1.021277 (2450 200);
DISPLAY INVISIBLE (2450 200);
FORCEPROP 2 LAST $SEC 1
J 0
(2450 200);
DISPLAY 0.680851 (2450 200);
PAINT MONO (2450 200);
DISPLAY INVISIBLE (2450 200);
FORCEPROP 2 LAST CDS_SEC 1
J 0
(2450 200);
DISPLAY 1.021277 (2450 200);
DISPLAY INVISIBLE (2450 200);
FORCEADD UNIVERSAL_GND..1
(4250 -350);
FORCEPROP 3 LASTPIN (4250 -300) SIG_NAME GND\g
J 0
(4260 -290);
DISPLAY 0.659574 (4260 -290);
PAINT MONO (4260 -290);
DISPLAY INVISIBLE (4260 -290);
FORCEPROP 2 LAST ROOM IO_SLOT
J 1
(4025 -275);
DISPLAY 0.744681 (4025 -275);
DISPLAY INVISIBLE (4025 -275);
FORCEPROP 1 LAST PATH I126
J 0
(4325 -350);
DISPLAY 0.872340 (4325 -350);
PAINT AQUA (4325 -350);
DISPLAY INVISIBLE (4325 -350);
FORCEPROP 1 LAST HDL_POWER GND
J 1
(4275 -425);
DISPLAY 0.872340 (4275 -425);
PAINT GREEN (4275 -425);
DISPLAY INVISIBLE (4275 -425);
FORCEPROP 2 LAST CDS_LIB logical_power
J 0
(4250 -350);
PAINT MONO (4250 -350);
DISPLAY INVISIBLE (4250 -350);
FORCEADD Q_CAP..1
(4250 0);
FORCEPROP 1 LAST PART_NUMBER CH6101MEB01
J 0
(4300 -150);
DISPLAY 0.638298 (4300 -150);
DISPLAY INVISIBLE (4300 -150);
FORCEPROP 1 LAST VALUE 10UF
J 0
(4300 50);
DISPLAY 0.638298 (4300 50);
FORCEPROP 1 LAST TOLERANCE 20%
J 0
(4300 -50);
DISPLAY 0.638298 (4300 -50);
FORCEPROP 1 LAST MATERIAL X6S
J 0
(4300 -100);
DISPLAY 0.638298 (4300 -100);
FORCEPROP 1 LAST PACK_TYPE C0402
J 0
(4300 -200);
DISPLAY 0.638298 (4300 -200);
FORCEPROP 1 LAST VOLTAGE 6.3V
J 0
(4300 0);
DISPLAY 0.638298 (4300 0);
FORCEPROP 1 LAST $LOCATION C1266
J 0
(4300 100);
DISPLAY 0.638298 (4300 100);
FORCEPROP 1 LASTPIN (4250 100) $PN 1
J 0
(4260 80);
DISPLAY 0.787234 (4260 80);
FORCEPROP 1 LASTPIN (4250 -100) $PN 2
J 0
(4260 -120);
DISPLAY 0.787234 (4260 -120);
FORCEPROP 1 LAST PATH I127
J 0
(4300 150);
DISPLAY 0.978723 (4300 150);
PAINT WHITE (4300 150);
DISPLAY INVISIBLE (4300 150);
FORCEPROP 2 LAST CDS_LIB pure_quanta
J 0
(4250 0);
PAINT MONO (4250 0);
DISPLAY INVISIBLE (4250 0);
FORCEPROP 2 LAST CDS_LOCATION C1266
J 0
(4300 200);
DISPLAY 1.021277 (4300 200);
DISPLAY INVISIBLE (4300 200);
FORCEPROP 2 LAST $SEC 1
J 0
(4300 200);
DISPLAY 0.680851 (4300 200);
PAINT MONO (4300 200);
DISPLAY INVISIBLE (4300 200);
FORCEPROP 2 LAST CDS_SEC 1
J 0
(4300 200);
DISPLAY 1.021277 (4300 200);
DISPLAY INVISIBLE (4300 200);
FORCEADD UNIVERSAL_POWER..1
(2375 4375);
FORCEPROP 3 LASTPIN (2375 4325) SIG_NAME P1V05_PCH_AUX\g
J 0
(2385 4335);
DISPLAY 0.659574 (2385 4335);
PAINT MONO (2385 4335);
DISPLAY INVISIBLE (2385 4335);
FORCEPROP 1 LAST HDL_POWER P1V05_PCH_AUX
J 1
(2375 4425);
DISPLAY 0.872340 (2375 4425);
PAINT GREEN (2375 4425);
FORCEPROP 1 LAST PATH I128
J 0
(2425 4400);
DISPLAY 0.872340 (2425 4400);
PAINT AQUA (2425 4400);
DISPLAY INVISIBLE (2425 4400);
FORCEPROP 2 LAST CDS_LIB logical_power
J 0
(2375 4375);
PAINT MONO (2375 4375);
DISPLAY INVISIBLE (2375 4375);
FORCEADD Q_RES..1
(3150 3950);
FORCEPROP 1 LAST PART_NUMBER CS00002JB13
J 0
(3050 4025);
DISPLAY 0.404255 (3050 4025);
DISPLAY INVISIBLE (3050 4025);
FORCEPROP 1 LAST TOLERANCE 5%
J 0
(3325 3950);
DISPLAY 0.510638 (3325 3950);
FORCEPROP 1 LAST VALUE 0
J 2
(3300 3950);
DISPLAY 0.510638 (3300 3950);
FORCEPROP 1 LAST MATERIAL CHIP
J 0
(3400 3950);
DISPLAY 0.510638 (3400 3950);
FORCEPROP 1 LAST WATTAGE 1/16W
J 2
(3300 4075);
DISPLAY 0.404255 (3300 4075);
FORCEPROP 1 LAST PACK_TYPE 0402LF
J 0
(3050 4075);
DISPLAY 0.404255 (3050 4075);
FORCEPROP 1 LAST $LOCATION R1463
J 0
(2900 3950);
DISPLAY 0.638298 (2900 3950);
FORCEPROP 1 LASTPIN (3050 3950) $PN 1
J 0
(3062 3962);
DISPLAY 0.787234 (3062 3962);
FORCEPROP 1 LASTPIN (3250 3950) $PN 2
J 0
(3212 3962);
DISPLAY 0.787234 (3212 3962);
FORCEPROP 2 LAST CDS_LIB pure_quanta
J 0
(3150 3950);
PAINT MONO (3150 3950);
DISPLAY INVISIBLE (3150 3950);
FORCEPROP 1 LAST PATH I129
J 0
(3100 4100);
DISPLAY 0.978723 (3100 4100);
PAINT WHITE (3100 4100);
DISPLAY INVISIBLE (3100 4100);
FORCEPROP 2 LAST CDS_LOCATION R1463
J 0
(3100 4150);
DISPLAY 1.021277 (3100 4150);
DISPLAY INVISIBLE (3100 4150);
FORCEPROP 2 LAST $SEC 1
J 0
(3100 4150);
DISPLAY 0.680851 (3100 4150);
PAINT MONO (3100 4150);
DISPLAY INVISIBLE (3100 4150);
FORCEPROP 2 LAST CDS_SEC 1
J 0
(3100 4150);
DISPLAY 1.021277 (3100 4150);
DISPLAY INVISIBLE (3100 4150);
FORCEADD Q_CAP..1
(-400 3825);
FORCEPROP 1 LAST PART_NUMBER CH6101MEB01
J 0
(-350 3675);
DISPLAY 0.638298 (-350 3675);
DISPLAY INVISIBLE (-350 3675);
FORCEPROP 1 LAST VALUE 10UF
J 0
(-350 3875);
DISPLAY 0.638298 (-350 3875);
FORCEPROP 1 LAST MATERIAL X6S
J 0
(-350 3725);
DISPLAY 0.638298 (-350 3725);
FORCEPROP 1 LAST PACK_TYPE C0402
J 0
(-350 3625);
DISPLAY 0.638298 (-350 3625);
FORCEPROP 1 LAST TOLERANCE 20%
J 0
(-350 3775);
DISPLAY 0.638298 (-350 3775);
FORCEPROP 1 LAST VOLTAGE 6.3V
J 0
(-350 3825);
DISPLAY 0.638298 (-350 3825);
FORCEPROP 1 LAST $LOCATION C1228
J 0
(-350 3925);
DISPLAY 0.638298 (-350 3925);
FORCEPROP 1 LASTPIN (-400 3925) $PN 1
J 0
(-390 3905);
DISPLAY 0.787234 (-390 3905);
FORCEPROP 1 LASTPIN (-400 3725) $PN 2
J 0
(-390 3705);
DISPLAY 0.787234 (-390 3705);
FORCEPROP 1 LAST PATH I13
J 0
(-350 3975);
DISPLAY 0.978723 (-350 3975);
PAINT WHITE (-350 3975);
DISPLAY INVISIBLE (-350 3975);
FORCEPROP 2 LAST CDS_LIB pure_quanta
J 0
(-400 3825);
PAINT MONO (-400 3825);
DISPLAY INVISIBLE (-400 3825);
FORCEPROP 2 LAST CDS_LOCATION C1228
J 0
(-350 4025);
DISPLAY 1.021277 (-350 4025);
DISPLAY INVISIBLE (-350 4025);
FORCEPROP 2 LAST $SEC 1
J 0
(-350 4025);
DISPLAY 0.680851 (-350 4025);
PAINT MONO (-350 4025);
DISPLAY INVISIBLE (-350 4025);
FORCEPROP 2 LAST CDS_SEC 1
J 0
(-350 4025);
DISPLAY 1.021277 (-350 4025);
DISPLAY INVISIBLE (-350 4025);
FORCEADD UNIVERSAL_POWER..1
(3950 4350);
FORCEPROP 3 LASTPIN (3950 4300) SIG_NAME P1V05_PCH_PLL_AUX\g
J 0
(3960 4310);
DISPLAY 0.659574 (3960 4310);
PAINT MONO (3960 4310);
DISPLAY INVISIBLE (3960 4310);
FORCEPROP 1 LAST HDL_POWER P1V05_PCH_PLL_AUX
J 1
(3950 4400);
DISPLAY 0.872340 (3950 4400);
PAINT GREEN (3950 4400);
FORCEPROP 1 LAST PATH I130
J 0
(4000 4375);
DISPLAY 0.872340 (4000 4375);
PAINT AQUA (4000 4375);
DISPLAY INVISIBLE (4000 4375);
FORCEPROP 2 LAST CDS_LIB logical_power
J 0
(3950 4350);
PAINT MONO (3950 4350);
DISPLAY INVISIBLE (3950 4350);
FORCEADD Q_CAP..1
(3550 3575);
FORCEPROP 1 LAST PART_NUMBER CH6101ME900
J 0
(3600 3425);
DISPLAY 0.638298 (3600 3425);
DISPLAY INVISIBLE (3600 3425);
FORCEPROP 1 LAST PACK_TYPE C0603
J 0
(3600 3375);
DISPLAY 0.638298 (3600 3375);
FORCEPROP 1 LAST MATERIAL X6S
J 0
(3600 3475);
DISPLAY 0.638298 (3600 3475);
FORCEPROP 1 LAST TOLERANCE 20%
J 0
(3600 3525);
DISPLAY 0.638298 (3600 3525);
FORCEPROP 1 LAST VOLTAGE 6.3V
J 0
(3600 3575);
DISPLAY 0.638298 (3600 3575);
FORCEPROP 1 LAST VALUE 10UF
J 0
(3600 3625);
DISPLAY 0.638298 (3600 3625);
FORCEPROP 1 LAST $LOCATION C1260
J 0
(3600 3675);
DISPLAY 0.787234 (3600 3675);
FORCEPROP 1 LASTPIN (3550 3675) $PN 1
J 0
(3560 3655);
DISPLAY 0.787234 (3560 3655);
FORCEPROP 1 LASTPIN (3550 3475) $PN 2
J 0
(3560 3455);
DISPLAY 0.787234 (3560 3455);
FORCEPROP 1 LAST PATH I131
J 0
(3600 3725);
DISPLAY 0.978723 (3600 3725);
PAINT WHITE (3600 3725);
DISPLAY INVISIBLE (3600 3725);
FORCEPROP 2 LAST CDS_LIB pure_quanta
J 0
(3550 3575);
PAINT MONO (3550 3575);
DISPLAY INVISIBLE (3550 3575);
FORCEPROP 2 LAST CDS_LOCATION C1260
J 0
(3600 3775);
DISPLAY 1.021277 (3600 3775);
DISPLAY INVISIBLE (3600 3775);
FORCEPROP 2 LAST $SEC 1
J 0
(3600 3775);
DISPLAY 0.680851 (3600 3775);
PAINT MONO (3600 3775);
DISPLAY INVISIBLE (3600 3775);
FORCEPROP 2 LAST CDS_SEC 1
J 0
(3600 3775);
DISPLAY 1.021277 (3600 3775);
DISPLAY INVISIBLE (3600 3775);
FORCEADD UNIVERSAL_GND..1
(2375 3225);
FORCEPROP 3 LASTPIN (2375 3275) SIG_NAME GND\g
J 0
(2385 3285);
DISPLAY 0.659574 (2385 3285);
PAINT MONO (2385 3285);
DISPLAY INVISIBLE (2385 3285);
FORCEPROP 2 LAST ROOM IO_SLOT
J 1
(2150 3300);
DISPLAY 0.744681 (2150 3300);
DISPLAY INVISIBLE (2150 3300);
FORCEPROP 1 LAST PATH I132
J 0
(2450 3225);
DISPLAY 0.872340 (2450 3225);
PAINT AQUA (2450 3225);
DISPLAY INVISIBLE (2450 3225);
FORCEPROP 1 LAST HDL_POWER GND
J 1
(2400 3150);
DISPLAY 0.872340 (2400 3150);
PAINT GREEN (2400 3150);
DISPLAY INVISIBLE (2400 3150);
FORCEPROP 2 LAST CDS_LIB logical_power
J 0
(2375 3225);
PAINT MONO (2375 3225);
DISPLAY INVISIBLE (2375 3225);
FORCEADD Q_CAP..1
(3950 3575);
FORCEPROP 1 LAST PART_NUMBER CH5101K1B01
J 0
(4000 3425);
DISPLAY 0.638298 (4000 3425);
DISPLAY INVISIBLE (4000 3425);
FORCEPROP 1 LAST TOLERANCE 10%
J 0
(4000 3525);
DISPLAY 0.638298 (4000 3525);
FORCEPROP 1 LAST VOLTAGE 6.3V
J 0
(4000 3575);
DISPLAY 0.638298 (4000 3575);
FORCEPROP 1 LAST MATERIAL EMPTY
J 0
(4000 3475);
DISPLAY 0.638298 (4000 3475);
PAINT RED (4000 3475);
FORCEPROP 1 LAST VALUE 1UF
J 0
(4000 3625);
DISPLAY 0.638298 (4000 3625);
FORCEPROP 1 LAST PACK_TYPE 0402
J 0
(4000 3375);
DISPLAY 0.638298 (4000 3375);
FORCEPROP 1 LAST $LOCATION C1264
J 0
(4000 3675);
DISPLAY 0.787234 (4000 3675);
FORCEPROP 1 LASTPIN (3950 3675) $PN 1
J 0
(3960 3655);
DISPLAY 0.787234 (3960 3655);
FORCEPROP 1 LASTPIN (3950 3475) $PN 2
J 0
(3960 3455);
DISPLAY 0.787234 (3960 3455);
FORCEPROP 1 LAST PATH I133
J 0
(4000 3725);
DISPLAY 0.978723 (4000 3725);
PAINT WHITE (4000 3725);
DISPLAY INVISIBLE (4000 3725);
FORCEPROP 2 LAST CDS_LIB pure_quanta
J 0
(3950 3575);
PAINT MONO (3950 3575);
DISPLAY INVISIBLE (3950 3575);
FORCEPROP 2 LAST CDS_LOCATION C1264
J 0
(4000 3775);
DISPLAY 1.021277 (4000 3775);
DISPLAY INVISIBLE (4000 3775);
FORCEPROP 2 LAST $SEC 1
J 0
(4000 3775);
DISPLAY 0.680851 (4000 3775);
PAINT MONO (4000 3775);
DISPLAY INVISIBLE (4000 3775);
FORCEPROP 2 LAST CDS_SEC 1
J 0
(4000 3775);
DISPLAY 1.021277 (4000 3775);
DISPLAY INVISIBLE (4000 3775);
FORCEADD UNIVERSAL_GND..1
(3950 3225);
FORCEPROP 3 LASTPIN (3950 3275) SIG_NAME GND\g
J 0
(3960 3285);
DISPLAY 0.659574 (3960 3285);
PAINT MONO (3960 3285);
DISPLAY INVISIBLE (3960 3285);
FORCEPROP 2 LAST ROOM IO_SLOT
J 1
(3725 3300);
DISPLAY 0.744681 (3725 3300);
DISPLAY INVISIBLE (3725 3300);
FORCEPROP 1 LAST PATH I134
J 0
(4025 3225);
DISPLAY 0.872340 (4025 3225);
PAINT AQUA (4025 3225);
DISPLAY INVISIBLE (4025 3225);
FORCEPROP 1 LAST HDL_POWER GND
J 1
(3975 3150);
DISPLAY 0.872340 (3975 3150);
PAINT GREEN (3975 3150);
DISPLAY INVISIBLE (3975 3150);
FORCEPROP 2 LAST CDS_LIB logical_power
J 0
(3950 3225);
PAINT MONO (3950 3225);
DISPLAY INVISIBLE (3950 3225);
FORCEADD Q_CAP..1
(3025 3575);
FORCEPROP 1 LAST PART_NUMBER CH5101K1B01
J 0
(3075 3425);
DISPLAY 0.638298 (3075 3425);
DISPLAY INVISIBLE (3075 3425);
FORCEPROP 1 LAST VALUE 1UF
J 0
(3075 3625);
DISPLAY 0.638298 (3075 3625);
FORCEPROP 1 LAST PACK_TYPE 0402
J 0
(3075 3375);
DISPLAY 0.638298 (3075 3375);
FORCEPROP 1 LAST MATERIAL EMPTY
J 0
(3075 3475);
DISPLAY 0.638298 (3075 3475);
PAINT RED (3075 3475);
FORCEPROP 1 LAST TOLERANCE 10%
J 0
(3075 3525);
DISPLAY 0.638298 (3075 3525);
FORCEPROP 1 LAST VOLTAGE 6.3V
J 0
(3075 3575);
DISPLAY 0.638298 (3075 3575);
FORCEPROP 1 LAST $LOCATION C1256
J 0
(3075 3675);
DISPLAY 0.787234 (3075 3675);
FORCEPROP 1 LASTPIN (3025 3675) $PN 1
J 0
(3035 3655);
DISPLAY 0.787234 (3035 3655);
FORCEPROP 1 LASTPIN (3025 3475) $PN 2
J 0
(3035 3455);
DISPLAY 0.787234 (3035 3455);
FORCEPROP 2 LAST CDS_LIB pure_quanta
J 0
(3025 3575);
PAINT MONO (3025 3575);
DISPLAY INVISIBLE (3025 3575);
FORCEPROP 1 LAST PATH I136
J 0
(3075 3725);
DISPLAY 0.978723 (3075 3725);
PAINT WHITE (3075 3725);
DISPLAY INVISIBLE (3075 3725);
FORCEPROP 2 LAST CDS_LOCATION C1256
J 0
(3075 3775);
DISPLAY 1.021277 (3075 3775);
DISPLAY INVISIBLE (3075 3775);
FORCEPROP 2 LAST $SEC 1
J 0
(3075 3775);
DISPLAY 0.680851 (3075 3775);
PAINT MONO (3075 3775);
DISPLAY INVISIBLE (3075 3775);
FORCEPROP 2 LAST CDS_SEC 1
J 0
(3075 3775);
DISPLAY 1.021277 (3075 3775);
DISPLAY INVISIBLE (3075 3775);
FORCEADD Q_CAP..1
(2375 3575);
FORCEPROP 1 LAST PART_NUMBER CH5101K1B01
J 0
(2425 3425);
DISPLAY 0.638298 (2425 3425);
DISPLAY INVISIBLE (2425 3425);
FORCEPROP 1 LAST VALUE 1UF
J 0
(2425 3625);
DISPLAY 0.638298 (2425 3625);
FORCEPROP 1 LAST PACK_TYPE 0402
J 0
(2425 3375);
DISPLAY 0.638298 (2425 3375);
FORCEPROP 1 LAST TOLERANCE 10%
J 0
(2425 3525);
DISPLAY 0.638298 (2425 3525);
FORCEPROP 1 LAST VOLTAGE 6.3V
J 0
(2425 3575);
DISPLAY 0.638298 (2425 3575);
FORCEPROP 1 LAST MATERIAL EMPTY
J 0
(2425 3475);
DISPLAY 0.638298 (2425 3475);
PAINT RED (2425 3475);
FORCEPROP 1 LAST $LOCATION C1250
J 0
(2425 3675);
DISPLAY 0.787234 (2425 3675);
FORCEPROP 1 LASTPIN (2375 3675) $PN 1
J 0
(2385 3655);
DISPLAY 0.787234 (2385 3655);
FORCEPROP 1 LASTPIN (2375 3475) $PN 2
J 0
(2385 3455);
DISPLAY 0.787234 (2385 3455);
FORCEPROP 2 LAST CDS_LIB pure_quanta
J 0
(2375 3575);
PAINT MONO (2375 3575);
DISPLAY INVISIBLE (2375 3575);
FORCEPROP 1 LAST PATH I137
J 0
(2425 3725);
DISPLAY 0.978723 (2425 3725);
PAINT WHITE (2425 3725);
DISPLAY INVISIBLE (2425 3725);
FORCEPROP 2 LAST CDS_LOCATION C1250
J 0
(2425 3775);
DISPLAY 1.021277 (2425 3775);
DISPLAY INVISIBLE (2425 3775);
FORCEPROP 2 LAST $SEC 1
J 0
(2425 3775);
DISPLAY 0.680851 (2425 3775);
PAINT MONO (2425 3775);
DISPLAY INVISIBLE (2425 3775);
FORCEPROP 2 LAST CDS_SEC 1
J 0
(2425 3775);
DISPLAY 1.021277 (2425 3775);
DISPLAY INVISIBLE (2425 3775);
FORCEADD UNIVERSAL_POWER..1
(2425 1425);
FORCEPROP 3 LASTPIN (2425 1375) SIG_NAME P1V8_PCH_AUX\g
J 0
(2435 1385);
DISPLAY 0.659574 (2435 1385);
PAINT MONO (2435 1385);
DISPLAY INVISIBLE (2435 1385);
FORCEPROP 1 LAST HDL_POWER P1V8_PCH_AUX
J 1
(2425 1475);
DISPLAY 0.872340 (2425 1475);
PAINT GREEN (2425 1475);
FORCEPROP 1 LAST PATH I138
J 0
(2475 1450);
DISPLAY 0.872340 (2475 1450);
PAINT AQUA (2475 1450);
DISPLAY INVISIBLE (2475 1450);
FORCEPROP 2 LAST CDS_LIB logical_power
J 0
(2425 1425);
PAINT MONO (2425 1425);
DISPLAY INVISIBLE (2425 1425);
FORCEADD UNIVERSAL_POWER..1
(4000 1400);
FORCEPROP 3 LASTPIN (4000 1350) SIG_NAME P1V8_PCH_PLL_AUX\g
J 0
(4010 1360);
DISPLAY 0.659574 (4010 1360);
PAINT MONO (4010 1360);
DISPLAY INVISIBLE (4010 1360);
FORCEPROP 1 LAST HDL_POWER P1V8_PCH_PLL_AUX
J 1
(4000 1450);
DISPLAY 0.872340 (4000 1450);
PAINT GREEN (4000 1450);
FORCEPROP 1 LAST PATH I139
J 0
(4050 1425);
DISPLAY 0.872340 (4050 1425);
PAINT AQUA (4050 1425);
DISPLAY INVISIBLE (4050 1425);
FORCEPROP 2 LAST CDS_LIB logical_power
J 0
(4000 1400);
PAINT MONO (4000 1400);
DISPLAY INVISIBLE (4000 1400);
FORCEADD UNIVERSAL_GND..1
(-400 3475);
FORCEPROP 3 LASTPIN (-400 3525) SIG_NAME GND\g
J 0
(-390 3535);
DISPLAY 0.659574 (-390 3535);
PAINT MONO (-390 3535);
DISPLAY INVISIBLE (-390 3535);
FORCEPROP 2 LAST ROOM IO_SLOT
J 1
(-625 3550);
DISPLAY 0.744681 (-625 3550);
DISPLAY INVISIBLE (-625 3550);
FORCEPROP 1 LAST PATH I14
J 0
(-325 3475);
DISPLAY 0.872340 (-325 3475);
PAINT AQUA (-325 3475);
DISPLAY INVISIBLE (-325 3475);
FORCEPROP 1 LAST HDL_POWER GND
J 1
(-375 3400);
DISPLAY 0.872340 (-375 3400);
PAINT GREEN (-375 3400);
DISPLAY INVISIBLE (-375 3400);
FORCEPROP 2 LAST CDS_LIB logical_power
J 0
(-400 3475);
PAINT MONO (-400 3475);
DISPLAY INVISIBLE (-400 3475);
FORCEADD Q_CAP..1
(4000 900);
FORCEPROP 1 LAST PART_NUMBER CH5101K1B01
J 0
(4050 750);
DISPLAY 0.638298 (4050 750);
DISPLAY INVISIBLE (4050 750);
FORCEPROP 1 LAST MATERIAL EMPTY
J 0
(4050 800);
DISPLAY 0.638298 (4050 800);
PAINT RED (4050 800);
FORCEPROP 1 LAST PACK_TYPE 0402
J 0
(4050 700);
DISPLAY 0.638298 (4050 700);
FORCEPROP 1 LAST VOLTAGE 6.3V
J 0
(4050 900);
DISPLAY 0.638298 (4050 900);
FORCEPROP 1 LAST VALUE 1UF
J 0
(4050 950);
DISPLAY 0.638298 (4050 950);
FORCEPROP 1 LAST TOLERANCE 10%
J 0
(4050 850);
DISPLAY 0.638298 (4050 850);
FORCEPROP 1 LAST $LOCATION C1265
J 0
(4050 1000);
DISPLAY 0.978723 (4050 1000);
FORCEPROP 1 LASTPIN (4000 1000) $PN 1
J 0
(4010 980);
DISPLAY 0.787234 (4010 980);
FORCEPROP 1 LASTPIN (4000 800) $PN 2
J 0
(4010 780);
DISPLAY 0.787234 (4010 780);
FORCEPROP 1 LAST PATH I140
J 0
(4050 1050);
DISPLAY 0.978723 (4050 1050);
PAINT WHITE (4050 1050);
DISPLAY INVISIBLE (4050 1050);
FORCEPROP 2 LAST CDS_LIB pure_quanta
J 0
(4000 900);
PAINT MONO (4000 900);
DISPLAY INVISIBLE (4000 900);
FORCEPROP 2 LAST CDS_LOCATION C1265
J 0
(4050 1100);
DISPLAY 1.021277 (4050 1100);
DISPLAY INVISIBLE (4050 1100);
FORCEPROP 2 LAST $SEC 1
J 0
(4050 1100);
DISPLAY 0.680851 (4050 1100);
PAINT MONO (4050 1100);
DISPLAY INVISIBLE (4050 1100);
FORCEPROP 2 LAST CDS_SEC 1
J 0
(4050 1100);
DISPLAY 1.021277 (4050 1100);
DISPLAY INVISIBLE (4050 1100);
FORCEADD UNIVERSAL_GND..1
(4000 550);
FORCEPROP 3 LASTPIN (4000 600) SIG_NAME GND\g
J 0
(4010 610);
DISPLAY 0.659574 (4010 610);
PAINT MONO (4010 610);
DISPLAY INVISIBLE (4010 610);
FORCEPROP 2 LAST ROOM IO_SLOT
J 1
(3775 625);
DISPLAY 0.744681 (3775 625);
DISPLAY INVISIBLE (3775 625);
FORCEPROP 1 LAST PATH I141
J 0
(4075 550);
DISPLAY 0.872340 (4075 550);
PAINT AQUA (4075 550);
DISPLAY INVISIBLE (4075 550);
FORCEPROP 1 LAST HDL_POWER GND
J 1
(4025 475);
DISPLAY 0.872340 (4025 475);
PAINT GREEN (4025 475);
DISPLAY INVISIBLE (4025 475);
FORCEPROP 2 LAST CDS_LIB logical_power
J 0
(4000 550);
PAINT MONO (4000 550);
DISPLAY INVISIBLE (4000 550);
FORCEADD Q_CAP..1
(3600 900);
FORCEPROP 1 LAST PART_NUMBER CH6101ME900
J 0
(3650 750);
DISPLAY 0.638298 (3650 750);
DISPLAY INVISIBLE (3650 750);
FORCEPROP 1 LAST PACK_TYPE C0603
J 0
(3650 700);
DISPLAY 0.638298 (3650 700);
FORCEPROP 1 LAST VALUE 10UF
J 0
(3650 950);
DISPLAY 0.638298 (3650 950);
FORCEPROP 1 LAST VOLTAGE 6.3V
J 0
(3650 900);
DISPLAY 0.638298 (3650 900);
FORCEPROP 1 LAST TOLERANCE 20%
J 0
(3650 850);
DISPLAY 0.638298 (3650 850);
FORCEPROP 1 LAST MATERIAL X6S
J 0
(3650 800);
DISPLAY 0.638298 (3650 800);
FORCEPROP 1 LAST $LOCATION C1261
J 0
(3650 1000);
DISPLAY 0.978723 (3650 1000);
FORCEPROP 1 LASTPIN (3600 1000) $PN 1
J 0
(3610 980);
DISPLAY 0.787234 (3610 980);
FORCEPROP 1 LASTPIN (3600 800) $PN 2
J 0
(3610 780);
DISPLAY 0.787234 (3610 780);
FORCEPROP 1 LAST PATH I142
J 0
(3650 1050);
DISPLAY 0.978723 (3650 1050);
PAINT WHITE (3650 1050);
DISPLAY INVISIBLE (3650 1050);
FORCEPROP 2 LAST CDS_LIB pure_quanta
J 0
(3600 900);
PAINT MONO (3600 900);
DISPLAY INVISIBLE (3600 900);
FORCEPROP 2 LAST CDS_LOCATION C1261
J 0
(3650 1100);
DISPLAY 1.021277 (3650 1100);
DISPLAY INVISIBLE (3650 1100);
FORCEPROP 2 LAST $SEC 1
J 0
(3650 1100);
DISPLAY 0.680851 (3650 1100);
PAINT MONO (3650 1100);
DISPLAY INVISIBLE (3650 1100);
FORCEPROP 2 LAST CDS_SEC 1
J 0
(3650 1100);
DISPLAY 1.021277 (3650 1100);
DISPLAY INVISIBLE (3650 1100);
FORCEADD UNIVERSAL_GND..1
(2425 500);
FORCEPROP 3 LASTPIN (2425 550) SIG_NAME GND\g
J 0
(2435 560);
DISPLAY 0.659574 (2435 560);
PAINT MONO (2435 560);
DISPLAY INVISIBLE (2435 560);
FORCEPROP 2 LAST ROOM IO_SLOT
J 1
(2200 575);
DISPLAY 0.744681 (2200 575);
DISPLAY INVISIBLE (2200 575);
FORCEPROP 1 LAST PATH I143
J 0
(2500 500);
DISPLAY 0.872340 (2500 500);
PAINT AQUA (2500 500);
DISPLAY INVISIBLE (2500 500);
FORCEPROP 1 LAST HDL_POWER GND
J 1
(2450 425);
DISPLAY 0.872340 (2450 425);
PAINT GREEN (2450 425);
DISPLAY INVISIBLE (2450 425);
FORCEPROP 2 LAST CDS_LIB logical_power
J 0
(2425 500);
PAINT MONO (2425 500);
DISPLAY INVISIBLE (2425 500);
FORCEADD Q_RES..1
(3200 1275);
FORCEPROP 1 LAST PART_NUMBER CS00002JB13
J 0
(3100 1350);
DISPLAY 0.404255 (3100 1350);
DISPLAY INVISIBLE (3100 1350);
FORCEPROP 1 LAST PACK_TYPE 0402LF
J 0
(3100 1400);
DISPLAY 0.404255 (3100 1400);
FORCEPROP 1 LAST WATTAGE 1/16W
J 2
(3350 1400);
DISPLAY 0.404255 (3350 1400);
FORCEPROP 1 LAST MATERIAL CHIP
J 0
(3450 1275);
DISPLAY 0.510638 (3450 1275);
FORCEPROP 1 LAST TOLERANCE 5%
J 0
(3375 1275);
DISPLAY 0.510638 (3375 1275);
FORCEPROP 1 LAST VALUE 0
J 2
(3350 1275);
DISPLAY 0.510638 (3350 1275);
FORCEPROP 1 LAST $LOCATION R1464
J 0
(2950 1275);
DISPLAY 0.638298 (2950 1275);
FORCEPROP 1 LASTPIN (3100 1275) $PN 1
J 0
(3112 1287);
DISPLAY 0.787234 (3112 1287);
FORCEPROP 1 LASTPIN (3300 1275) $PN 2
J 0
(3262 1287);
DISPLAY 0.787234 (3262 1287);
FORCEPROP 1 LAST PATH I144
J 0
(3150 1425);
DISPLAY 0.978723 (3150 1425);
PAINT WHITE (3150 1425);
DISPLAY INVISIBLE (3150 1425);
FORCEPROP 2 LAST CDS_LIB pure_quanta
J 0
(3200 1275);
PAINT MONO (3200 1275);
DISPLAY INVISIBLE (3200 1275);
FORCEPROP 2 LAST CDS_LOCATION R1464
J 0
(3150 1475);
DISPLAY 1.021277 (3150 1475);
DISPLAY INVISIBLE (3150 1475);
FORCEPROP 2 LAST $SEC 1
J 0
(3150 1475);
DISPLAY 0.680851 (3150 1475);
PAINT MONO (3150 1475);
DISPLAY INVISIBLE (3150 1475);
FORCEPROP 2 LAST CDS_SEC 1
J 0
(3150 1475);
DISPLAY 1.021277 (3150 1475);
DISPLAY INVISIBLE (3150 1475);
FORCEADD Q_INDUCTOR..1
(2750 1100);
FORCEPROP 1 LAST PART_NUMBER CX8PG121009
J 0
(2625 985);
DISPLAY 0.574468 (2625 985);
PAINT GREEN (2625 985);
DISPLAY INVISIBLE (2625 985);
FORCEPROP 2 LAST VALUE BLM18PG121SN1D/2000MA
J 0
(2625 1150);
DISPLAY 0.510638 (2625 1150);
FORCEPROP 1 LAST MATERIAL EMPTY
J 0
(2625 1030);
DISPLAY 0.574468 (2625 1030);
PAINT RED (2625 1030);
FORCEPROP 2 LAST PACK_TYPE SMLF
J 0
(2625 1200);
DISPLAY 0.510638 (2625 1200);
FORCEPROP 1 LAST $LOCATION L10
J 0
(2500 1085);
DISPLAY 0.723404 (2500 1085);
PAINT GREEN (2500 1085);
FORCEPROP 2 LASTPIN (2650 1075) $PN 1
J 2
(2640 1085);
DISPLAY 0.808511 (2640 1085);
FORCEPROP 2 LASTPIN (2850 1075) $PN 2
J 0
(2860 1085);
DISPLAY 0.808511 (2860 1085);
FORCEPROP 1 LAST PATH I145
J 0
(2825 1155);
DISPLAY 0.723404 (2825 1155);
PAINT GREEN (2825 1155);
DISPLAY INVISIBLE (2825 1155);
FORCEPROP 1 LAST NEEDS_NO_SIZE TRUE
J 0
(2750 1100);
DISPLAY 0.468085 (2750 1100);
PAINT GREEN (2750 1100);
DISPLAY INVISIBLE (2750 1100);
FORCEPROP 2 LAST CDS_LIB pure_quanta
J 0
(2750 1100);
PAINT MONO (2750 1100);
DISPLAY INVISIBLE (2750 1100);
FORCEPROP 2 LAST CDS_LOCATION L10
J 0
(2625 1225);
DISPLAY 1.021277 (2625 1225);
DISPLAY INVISIBLE (2625 1225);
FORCEPROP 2 LAST $SEC 1
J 0
(2625 1225);
DISPLAY 0.680851 (2625 1225);
PAINT MONO (2625 1225);
DISPLAY INVISIBLE (2625 1225);
FORCEPROP 2 LAST CDS_SEC 1
J 0
(2625 1225);
DISPLAY 1.021277 (2625 1225);
DISPLAY INVISIBLE (2625 1225);
FORCEADD Q_CAP..1
(3075 900);
FORCEPROP 1 LAST PART_NUMBER CH5101K1B01
J 0
(3125 750);
DISPLAY 0.638298 (3125 750);
DISPLAY INVISIBLE (3125 750);
FORCEPROP 1 LAST MATERIAL EMPTY
J 0
(3125 800);
DISPLAY 0.638298 (3125 800);
PAINT RED (3125 800);
FORCEPROP 1 LAST PACK_TYPE 0402
J 0
(3125 700);
DISPLAY 0.638298 (3125 700);
FORCEPROP 1 LAST VOLTAGE 6.3V
J 0
(3125 900);
DISPLAY 0.638298 (3125 900);
FORCEPROP 1 LAST VALUE 1UF
J 0
(3125 950);
DISPLAY 0.638298 (3125 950);
FORCEPROP 1 LAST TOLERANCE 10%
J 0
(3125 850);
DISPLAY 0.638298 (3125 850);
FORCEPROP 1 LAST $LOCATION C1257
J 0
(3125 1000);
DISPLAY 0.978723 (3125 1000);
FORCEPROP 1 LASTPIN (3075 1000) $PN 1
J 0
(3085 980);
DISPLAY 0.787234 (3085 980);
FORCEPROP 1 LASTPIN (3075 800) $PN 2
J 0
(3085 780);
DISPLAY 0.787234 (3085 780);
FORCEPROP 1 LAST PATH I146
J 0
(3125 1050);
DISPLAY 0.978723 (3125 1050);
PAINT WHITE (3125 1050);
DISPLAY INVISIBLE (3125 1050);
FORCEPROP 2 LAST CDS_LIB pure_quanta
J 0
(3075 900);
PAINT MONO (3075 900);
DISPLAY INVISIBLE (3075 900);
FORCEPROP 2 LAST CDS_LOCATION C1257
J 0
(3125 1100);
DISPLAY 1.021277 (3125 1100);
DISPLAY INVISIBLE (3125 1100);
FORCEPROP 2 LAST $SEC 1
J 0
(3125 1100);
DISPLAY 0.680851 (3125 1100);
PAINT MONO (3125 1100);
DISPLAY INVISIBLE (3125 1100);
FORCEPROP 2 LAST CDS_SEC 1
J 0
(3125 1100);
DISPLAY 1.021277 (3125 1100);
DISPLAY INVISIBLE (3125 1100);
FORCEADD Q_CAP..1
(2425 900);
FORCEPROP 1 LAST PART_NUMBER CH5101K1B01
J 0
(2475 750);
DISPLAY 0.638298 (2475 750);
DISPLAY INVISIBLE (2475 750);
FORCEPROP 1 LAST PACK_TYPE 0402
J 0
(2475 700);
DISPLAY 0.638298 (2475 700);
FORCEPROP 1 LAST VALUE 1UF
J 0
(2475 950);
DISPLAY 0.638298 (2475 950);
FORCEPROP 1 LAST VOLTAGE 6.3V
J 0
(2475 900);
DISPLAY 0.638298 (2475 900);
FORCEPROP 1 LAST TOLERANCE 10%
J 0
(2475 850);
DISPLAY 0.638298 (2475 850);
FORCEPROP 1 LAST MATERIAL EMPTY
J 0
(2475 800);
DISPLAY 0.638298 (2475 800);
PAINT RED (2475 800);
FORCEPROP 1 LAST $LOCATION C1253
J 0
(2475 1000);
DISPLAY 0.978723 (2475 1000);
FORCEPROP 1 LASTPIN (2425 1000) $PN 1
J 0
(2435 980);
DISPLAY 0.787234 (2435 980);
FORCEPROP 1 LASTPIN (2425 800) $PN 2
J 0
(2435 780);
DISPLAY 0.787234 (2435 780);
FORCEPROP 1 LAST PATH I147
J 0
(2475 1050);
DISPLAY 0.978723 (2475 1050);
PAINT WHITE (2475 1050);
DISPLAY INVISIBLE (2475 1050);
FORCEPROP 2 LAST CDS_LIB pure_quanta
J 0
(2425 900);
PAINT MONO (2425 900);
DISPLAY INVISIBLE (2425 900);
FORCEPROP 2 LAST CDS_LOCATION C1253
J 0
(2475 1100);
DISPLAY 1.021277 (2475 1100);
DISPLAY INVISIBLE (2475 1100);
FORCEPROP 2 LAST $SEC 1
J 0
(2475 1100);
DISPLAY 0.680851 (2475 1100);
PAINT MONO (2475 1100);
DISPLAY INVISIBLE (2475 1100);
FORCEPROP 2 LAST CDS_SEC 1
J 0
(2475 1100);
DISPLAY 1.021277 (2475 1100);
DISPLAY INVISIBLE (2475 1100);
FORCEADD UNIVERSAL_POWER..1
(-900 1475);
FORCEPROP 3 LASTPIN (-900 1425) SIG_NAME P1V05_PCH_AUX\g
J 0
(-890 1435);
DISPLAY 0.659574 (-890 1435);
PAINT MONO (-890 1435);
DISPLAY INVISIBLE (-890 1435);
FORCEPROP 1 LAST HDL_POWER P1V05_PCH_AUX
J 1
(-900 1525);
DISPLAY 0.872340 (-900 1525);
PAINT GREEN (-900 1525);
FORCEPROP 1 LAST PATH I148
J 0
(-850 1500);
DISPLAY 0.872340 (-850 1500);
PAINT AQUA (-850 1500);
DISPLAY INVISIBLE (-850 1500);
FORCEPROP 2 LAST CDS_LIB logical_power
J 0
(-900 1475);
PAINT MONO (-900 1475);
DISPLAY INVISIBLE (-900 1475);
FORCEADD UNIVERSAL_POWER..1
(500 1450);
FORCEPROP 3 LASTPIN (500 1400) SIG_NAME P1V05_PCH_AUX\g
J 0
(510 1410);
DISPLAY 0.659574 (510 1410);
PAINT MONO (510 1410);
DISPLAY INVISIBLE (510 1410);
FORCEPROP 1 LAST HDL_POWER P1V05_PCH_AUX
J 1
(500 1500);
DISPLAY 0.872340 (500 1500);
PAINT GREEN (500 1500);
FORCEPROP 1 LAST PATH I149
J 0
(550 1475);
DISPLAY 0.872340 (550 1475);
PAINT AQUA (550 1475);
DISPLAY INVISIBLE (550 1475);
FORCEPROP 2 LAST CDS_LIB logical_power
J 0
(500 1450);
PAINT MONO (500 1450);
DISPLAY INVISIBLE (500 1450);
FORCEADD UNIVERSAL_POWER..1
(-2250 750);
FORCEPROP 3 LASTPIN (-2250 700) SIG_NAME P1V05_PCH_AUX\g
J 0
(-2240 710);
DISPLAY 0.659574 (-2240 710);
PAINT MONO (-2240 710);
DISPLAY INVISIBLE (-2240 710);
FORCEPROP 1 LAST HDL_POWER P1V05_PCH_AUX
J 1
(-2250 800);
DISPLAY 0.872340 (-2250 800);
PAINT GREEN (-2250 800);
FORCEPROP 1 LAST PATH I150
J 0
(-2200 775);
DISPLAY 0.872340 (-2200 775);
PAINT AQUA (-2200 775);
DISPLAY INVISIBLE (-2200 775);
FORCEPROP 2 LAST CDS_LIB logical_power
J 0
(-2250 750);
PAINT MONO (-2250 750);
DISPLAY INVISIBLE (-2250 750);
FORCEADD Q_CAP..1
(4700 0);
FORCEPROP 1 LAST PART_NUMBER CH647KMEA04
J 0
(4750 -150);
DISPLAY 0.638298 (4750 -150);
DISPLAY INVISIBLE (4750 -150);
FORCEPROP 1 LAST VOLTAGE 4V
J 0
(4750 0);
DISPLAY 0.638298 (4750 0);
FORCEPROP 1 LAST MATERIAL X6S
J 0
(4750 -100);
DISPLAY 0.638298 (4750 -100);
FORCEPROP 1 LAST VALUE 47UF
J 0
(4750 50);
DISPLAY 0.638298 (4750 50);
FORCEPROP 1 LAST PACK_TYPE C0805
J 0
(4750 -200);
DISPLAY 0.638298 (4750 -200);
FORCEPROP 1 LAST TOLERANCE 20%
J 0
(4750 -50);
DISPLAY 0.638298 (4750 -50);
FORCEPROP 1 LAST LOCATION C1273
J 0
(4750 100);
DISPLAY 0.638298 (4750 100);
FORCEPROP 1 LASTPIN (4700 100) $PN 1
J 0
(4710 80);
DISPLAY 0.787234 (4710 80);
PAINT MONO (4710 80);
FORCEPROP 1 LASTPIN (4700 -100) $PN 2
J 0
(4710 -120);
DISPLAY 0.787234 (4710 -120);
PAINT MONO (4710 -120);
FORCEPROP 1 LAST PATH I151
J 0
(4750 150);
DISPLAY 0.978723 (4750 150);
PAINT WHITE (4750 150);
DISPLAY INVISIBLE (4750 150);
FORCEPROP 2 LAST CDS_LIB pure_quanta
J 0
(4700 0);
DISPLAY INVISIBLE (4700 0);
FORCEPROP 0 LAST $SEC 1
J 0
(4750 150);
DISPLAY 0.680851 (4750 150);
PAINT MONO (4750 150);
DISPLAY INVISIBLE (4750 150);
FORCEPROP 0 LAST CDS_SEC 1
J 0
(4750 150);
DISPLAY 1.021277 (4750 150);
DISPLAY INVISIBLE (4750 150);
FORCEADD Q_CAP..1
(50 3825);
FORCEPROP 1 LAST PART_NUMBER CH647KMEA04
J 0
(100 3675);
DISPLAY 0.638298 (100 3675);
DISPLAY INVISIBLE (100 3675);
FORCEPROP 1 LAST TOLERANCE 20%
J 0
(100 3775);
DISPLAY 0.638298 (100 3775);
FORCEPROP 1 LAST MATERIAL X6S
J 0
(100 3725);
DISPLAY 0.638298 (100 3725);
FORCEPROP 1 LAST VALUE 47UF
J 0
(100 3875);
DISPLAY 0.638298 (100 3875);
FORCEPROP 1 LAST VOLTAGE 4V
J 0
(100 3825);
DISPLAY 0.638298 (100 3825);
FORCEPROP 1 LAST PACK_TYPE C0805
J 0
(100 3625);
DISPLAY 0.638298 (100 3625);
FORCEPROP 1 LAST LOCATION C1244
J 0
(100 3925);
DISPLAY 0.638298 (100 3925);
FORCEPROP 1 LASTPIN (50 3925) $PN 1
J 0
(60 3905);
DISPLAY 0.787234 (60 3905);
PAINT MONO (60 3905);
FORCEPROP 1 LASTPIN (50 3725) $PN 2
J 0
(60 3705);
DISPLAY 0.787234 (60 3705);
PAINT MONO (60 3705);
FORCEPROP 1 LAST PATH I152
J 0
(100 3975);
DISPLAY 0.978723 (100 3975);
PAINT WHITE (100 3975);
DISPLAY INVISIBLE (100 3975);
FORCEPROP 2 LAST CDS_LIB pure_quanta
J 0
(50 3825);
DISPLAY INVISIBLE (50 3825);
FORCEPROP 0 LAST $SEC 1
J 0
(100 3975);
DISPLAY 0.680851 (100 3975);
PAINT MONO (100 3975);
DISPLAY INVISIBLE (100 3975);
FORCEPROP 0 LAST CDS_SEC 1
J 0
(100 3975);
DISPLAY 1.021277 (100 3975);
DISPLAY INVISIBLE (100 3975);
FORCEADD Q_CAP..1
(500 3825);
FORCEPROP 1 LAST PART_NUMBER CH647KMEA04
J 0
(550 3675);
DISPLAY 0.638298 (550 3675);
DISPLAY INVISIBLE (550 3675);
FORCEPROP 1 LAST MATERIAL X6S
J 0
(550 3725);
DISPLAY 0.638298 (550 3725);
FORCEPROP 1 LAST TOLERANCE 20%
J 0
(550 3775);
DISPLAY 0.638298 (550 3775);
FORCEPROP 1 LAST VALUE 47UF
J 0
(550 3875);
DISPLAY 0.638298 (550 3875);
FORCEPROP 1 LAST VOLTAGE 4V
J 0
(550 3825);
DISPLAY 0.638298 (550 3825);
FORCEPROP 1 LAST PACK_TYPE C0805
J 0
(550 3625);
DISPLAY 0.638298 (550 3625);
FORCEPROP 1 LAST LOCATION C1246
J 0
(550 3925);
DISPLAY 0.638298 (550 3925);
FORCEPROP 1 LASTPIN (500 3925) $PN 1
J 0
(510 3905);
DISPLAY 0.787234 (510 3905);
PAINT MONO (510 3905);
FORCEPROP 1 LASTPIN (500 3725) $PN 2
J 0
(510 3705);
DISPLAY 0.787234 (510 3705);
PAINT MONO (510 3705);
FORCEPROP 1 LAST PATH I153
J 0
(550 3975);
DISPLAY 0.978723 (550 3975);
PAINT WHITE (550 3975);
DISPLAY INVISIBLE (550 3975);
FORCEPROP 2 LAST CDS_LIB pure_quanta
J 0
(500 3825);
DISPLAY INVISIBLE (500 3825);
FORCEPROP 0 LAST $SEC 1
J 0
(550 3975);
DISPLAY 0.680851 (550 3975);
PAINT MONO (550 3975);
DISPLAY INVISIBLE (550 3975);
FORCEPROP 0 LAST CDS_SEC 1
J 0
(550 3975);
DISPLAY 1.021277 (550 3975);
DISPLAY INVISIBLE (550 3975);
FORCEADD Q_CAP..1
(500 1175);
FORCEPROP 1 LAST PART_NUMBER CH647KMEA04
J 0
(550 1025);
DISPLAY 0.638298 (550 1025);
DISPLAY INVISIBLE (550 1025);
FORCEPROP 1 LAST MATERIAL X6S
J 0
(550 1075);
DISPLAY 0.638298 (550 1075);
FORCEPROP 1 LAST VOLTAGE 4V
J 0
(550 1175);
DISPLAY 0.638298 (550 1175);
FORCEPROP 1 LAST TOLERANCE 20%
J 0
(550 1125);
DISPLAY 0.638298 (550 1125);
FORCEPROP 1 LAST VALUE 47UF
J 0
(550 1225);
DISPLAY 0.638298 (550 1225);
FORCEPROP 1 LAST PACK_TYPE C0805
J 0
(550 975);
DISPLAY 0.638298 (550 975);
FORCEPROP 1 LAST LOCATION C1247
J 0
(550 1275);
DISPLAY 0.787234 (550 1275);
FORCEPROP 1 LASTPIN (500 1275) $PN 1
J 0
(510 1255);
DISPLAY 0.787234 (510 1255);
PAINT MONO (510 1255);
FORCEPROP 1 LASTPIN (500 1075) $PN 2
J 0
(510 1055);
DISPLAY 0.787234 (510 1055);
PAINT MONO (510 1055);
FORCEPROP 1 LAST PATH I154
J 0
(550 1325);
DISPLAY 0.978723 (550 1325);
PAINT WHITE (550 1325);
DISPLAY INVISIBLE (550 1325);
FORCEPROP 2 LAST CDS_LIB pure_quanta
J 0
(500 1175);
DISPLAY INVISIBLE (500 1175);
FORCEPROP 0 LAST $SEC 1
J 0
(550 1325);
DISPLAY 0.680851 (550 1325);
PAINT MONO (550 1325);
DISPLAY INVISIBLE (550 1325);
FORCEPROP 0 LAST CDS_SEC 1
J 0
(550 1325);
DISPLAY 1.021277 (550 1325);
DISPLAY INVISIBLE (550 1325);
FORCEADD Q_CAP..1
(950 3825);
FORCEPROP 1 LAST PART_NUMBER CH647KMEA04
J 0
(1000 3675);
DISPLAY 0.638298 (1000 3675);
DISPLAY INVISIBLE (1000 3675);
FORCEPROP 1 LAST PACK_TYPE C0805
J 0
(1000 3625);
DISPLAY 0.638298 (1000 3625);
FORCEPROP 1 LAST VALUE 47UF
J 0
(1000 3875);
DISPLAY 0.638298 (1000 3875);
FORCEPROP 1 LAST VOLTAGE 4V
J 0
(1000 3825);
DISPLAY 0.638298 (1000 3825);
FORCEPROP 1 LAST MATERIAL X6S
J 0
(1000 3725);
DISPLAY 0.638298 (1000 3725);
FORCEPROP 1 LAST TOLERANCE 20%
J 0
(1000 3775);
DISPLAY 0.638298 (1000 3775);
FORCEPROP 1 LAST LOCATION C1248
J 0
(1000 3925);
DISPLAY 0.638298 (1000 3925);
FORCEPROP 1 LASTPIN (950 3925) $PN 1
J 0
(960 3905);
DISPLAY 0.787234 (960 3905);
PAINT MONO (960 3905);
FORCEPROP 1 LASTPIN (950 3725) $PN 2
J 0
(960 3705);
DISPLAY 0.787234 (960 3705);
PAINT MONO (960 3705);
FORCEPROP 1 LAST PATH I155
J 0
(1000 3975);
DISPLAY 0.978723 (1000 3975);
PAINT WHITE (1000 3975);
DISPLAY INVISIBLE (1000 3975);
FORCEPROP 2 LAST CDS_LIB pure_quanta
J 0
(950 3825);
DISPLAY INVISIBLE (950 3825);
FORCEPROP 0 LAST $SEC 1
J 0
(1000 3975);
DISPLAY 0.680851 (1000 3975);
PAINT MONO (1000 3975);
DISPLAY INVISIBLE (1000 3975);
FORCEPROP 0 LAST CDS_SEC 1
J 0
(1000 3975);
DISPLAY 1.021277 (1000 3975);
DISPLAY INVISIBLE (1000 3975);
FORCEADD Q_CAP..1
(950 1175);
FORCEPROP 1 LAST PART_NUMBER CH647KMEA04
J 0
(1000 1025);
DISPLAY 0.638298 (1000 1025);
DISPLAY INVISIBLE (1000 1025);
FORCEPROP 1 LAST MATERIAL X6S
J 0
(1000 1075);
DISPLAY 0.638298 (1000 1075);
FORCEPROP 1 LAST VALUE 47UF
J 0
(1000 1225);
DISPLAY 0.638298 (1000 1225);
FORCEPROP 1 LAST PACK_TYPE C0805
J 0
(1000 975);
DISPLAY 0.638298 (1000 975);
FORCEPROP 1 LAST VOLTAGE 4V
J 0
(1000 1175);
DISPLAY 0.638298 (1000 1175);
FORCEPROP 1 LAST TOLERANCE 20%
J 0
(1000 1125);
DISPLAY 0.638298 (1000 1125);
FORCEPROP 1 LAST LOCATION C1249
J 0
(1000 1275);
DISPLAY 0.638298 (1000 1275);
FORCEPROP 1 LASTPIN (950 1275) $PN 1
J 0
(960 1255);
DISPLAY 0.787234 (960 1255);
PAINT MONO (960 1255);
FORCEPROP 1 LASTPIN (950 1075) $PN 2
J 0
(960 1055);
DISPLAY 0.787234 (960 1055);
PAINT MONO (960 1055);
FORCEPROP 1 LAST PATH I156
J 0
(1000 1325);
DISPLAY 0.978723 (1000 1325);
PAINT WHITE (1000 1325);
DISPLAY INVISIBLE (1000 1325);
FORCEPROP 2 LAST CDS_LIB pure_quanta
J 0
(950 1175);
DISPLAY INVISIBLE (950 1175);
FORCEPROP 0 LAST $SEC 1
J 0
(1000 1325);
DISPLAY 0.680851 (1000 1325);
PAINT MONO (1000 1325);
DISPLAY INVISIBLE (1000 1325);
FORCEPROP 0 LAST CDS_SEC 1
J 0
(1000 1325);
DISPLAY 1.021277 (1000 1325);
DISPLAY INVISIBLE (1000 1325);
FORCEADD Q_CAP..1
(3275 2650);
FORCEPROP 1 LAST PART_NUMBER CH647KMEA04
J 0
(3325 2500);
DISPLAY 0.638298 (3325 2500);
DISPLAY INVISIBLE (3325 2500);
FORCEPROP 1 LAST VALUE 47UF
J 0
(3325 2700);
DISPLAY 0.638298 (3325 2700);
FORCEPROP 1 LAST PACK_TYPE C0805
J 0
(3325 2450);
DISPLAY 0.638298 (3325 2450);
FORCEPROP 1 LAST VOLTAGE 4V
J 0
(3325 2650);
DISPLAY 0.638298 (3325 2650);
FORCEPROP 1 LAST TOLERANCE 20%
J 0
(3325 2600);
DISPLAY 0.638298 (3325 2600);
FORCEPROP 1 LAST MATERIAL X6S
J 0
(3325 2550);
DISPLAY 0.638298 (3325 2550);
FORCEPROP 1 LAST LOCATION C1258
J 0
(3325 2750);
DISPLAY 0.638298 (3325 2750);
FORCEPROP 1 LASTPIN (3275 2750) $PN 1
J 0
(3285 2730);
DISPLAY 0.787234 (3285 2730);
PAINT MONO (3285 2730);
FORCEPROP 1 LASTPIN (3275 2550) $PN 2
J 0
(3285 2530);
DISPLAY 0.787234 (3285 2530);
PAINT MONO (3285 2530);
FORCEPROP 1 LAST PATH I157
J 0
(3325 2800);
DISPLAY 0.978723 (3325 2800);
PAINT WHITE (3325 2800);
DISPLAY INVISIBLE (3325 2800);
FORCEPROP 2 LAST CDS_LIB pure_quanta
J 0
(3275 2650);
DISPLAY INVISIBLE (3275 2650);
FORCEPROP 0 LAST $SEC 1
J 0
(3325 2800);
DISPLAY 0.680851 (3325 2800);
PAINT MONO (3325 2800);
DISPLAY INVISIBLE (3325 2800);
FORCEPROP 0 LAST CDS_SEC 1
J 0
(3325 2800);
DISPLAY 1.021277 (3325 2800);
DISPLAY INVISIBLE (3325 2800);
FORCEADD Q_CAP..1
(3300 0);
FORCEPROP 1 LAST PART_NUMBER CH647KMEA04
J 0
(3350 -150);
DISPLAY 0.638298 (3350 -150);
DISPLAY INVISIBLE (3350 -150);
FORCEPROP 1 LAST MATERIAL X6S
J 0
(3350 -100);
DISPLAY 0.638298 (3350 -100);
FORCEPROP 1 LAST VALUE 47UF
J 0
(3350 50);
DISPLAY 0.638298 (3350 50);
FORCEPROP 1 LAST PACK_TYPE C0805
J 0
(3350 -200);
DISPLAY 0.638298 (3350 -200);
FORCEPROP 1 LAST VOLTAGE 4V
J 0
(3350 0);
DISPLAY 0.638298 (3350 0);
FORCEPROP 1 LAST TOLERANCE 20%
J 0
(3350 -50);
DISPLAY 0.638298 (3350 -50);
FORCEPROP 1 LAST LOCATION C1259
J 0
(3350 100);
DISPLAY 0.638298 (3350 100);
FORCEPROP 1 LASTPIN (3300 100) $PN 1
J 0
(3310 80);
DISPLAY 0.787234 (3310 80);
PAINT MONO (3310 80);
FORCEPROP 1 LASTPIN (3300 -100) $PN 2
J 0
(3310 -120);
DISPLAY 0.787234 (3310 -120);
PAINT MONO (3310 -120);
FORCEPROP 1 LAST PATH I158
J 0
(3350 150);
DISPLAY 0.978723 (3350 150);
PAINT WHITE (3350 150);
DISPLAY INVISIBLE (3350 150);
FORCEPROP 2 LAST CDS_LIB pure_quanta
J 0
(3300 0);
DISPLAY INVISIBLE (3300 0);
FORCEPROP 0 LAST $SEC 1
J 0
(3350 150);
DISPLAY 0.680851 (3350 150);
PAINT MONO (3350 150);
DISPLAY INVISIBLE (3350 150);
FORCEPROP 0 LAST CDS_SEC 1
J 0
(3350 150);
DISPLAY 1.021277 (3350 150);
DISPLAY INVISIBLE (3350 150);
FORCEADD Q_CAP..1
(4700 2650);
FORCEPROP 1 LAST PART_NUMBER CH647KMEA04
J 0
(4750 2500);
DISPLAY 0.638298 (4750 2500);
DISPLAY INVISIBLE (4750 2500);
FORCEPROP 1 LAST VALUE 47UF
J 0
(4750 2700);
DISPLAY 0.638298 (4750 2700);
FORCEPROP 1 LAST VOLTAGE 4V
J 0
(4750 2650);
DISPLAY 0.638298 (4750 2650);
FORCEPROP 1 LAST MATERIAL X6S
J 0
(4750 2550);
DISPLAY 0.638298 (4750 2550);
FORCEPROP 1 LAST PACK_TYPE C0805
J 0
(4750 2450);
DISPLAY 0.638298 (4750 2450);
FORCEPROP 1 LAST TOLERANCE 20%
J 0
(4750 2600);
DISPLAY 0.638298 (4750 2600);
FORCEPROP 1 LAST LOCATION C1272
J 0
(4750 2750);
DISPLAY 0.638298 (4750 2750);
FORCEPROP 1 LASTPIN (4700 2750) $PN 1
J 0
(4710 2730);
DISPLAY 0.787234 (4710 2730);
PAINT MONO (4710 2730);
FORCEPROP 1 LASTPIN (4700 2550) $PN 2
J 0
(4710 2530);
DISPLAY 0.787234 (4710 2530);
PAINT MONO (4710 2530);
FORCEPROP 1 LAST PATH I159
J 0
(4750 2800);
DISPLAY 0.978723 (4750 2800);
PAINT WHITE (4750 2800);
DISPLAY INVISIBLE (4750 2800);
FORCEPROP 2 LAST CDS_LIB pure_quanta
J 0
(4700 2650);
DISPLAY INVISIBLE (4700 2650);
FORCEPROP 0 LAST $SEC 1
J 0
(4750 2800);
DISPLAY 0.680851 (4750 2800);
PAINT MONO (4750 2800);
DISPLAY INVISIBLE (4750 2800);
FORCEPROP 0 LAST CDS_SEC 1
J 0
(4750 2800);
DISPLAY 1.021277 (4750 2800);
DISPLAY INVISIBLE (4750 2800);
FORCEADD Q_CAP..1
(0 -725);
FORCEPROP 1 LAST PART_NUMBER CH6471MEA02
J 0
(50 -875);
DISPLAY 0.638298 (50 -875);
DISPLAY INVISIBLE (50 -875);
FORCEPROP 1 LAST TOLERANCE 20%
J 0
(50 -775);
DISPLAY 0.638298 (50 -775);
FORCEPROP 1 LAST VOLTAGE 6.3V
J 0
(50 -725);
DISPLAY 0.638298 (50 -725);
FORCEPROP 1 LAST PACK_TYPE C0805
J 0
(50 -925);
DISPLAY 0.638298 (50 -925);
FORCEPROP 1 LAST VALUE 47UF
J 0
(50 -675);
DISPLAY 0.638298 (50 -675);
FORCEPROP 1 LAST MATERIAL X6S
J 0
(50 -825);
DISPLAY 0.638298 (50 -825);
FORCEPROP 1 LAST LOCATION C1243
J 0
(50 -625);
DISPLAY 0.638298 (50 -625);
FORCEPROP 1 LASTPIN (0 -625) $PN 1
J 0
(10 -645);
DISPLAY 0.787234 (10 -645);
PAINT MONO (10 -645);
FORCEPROP 1 LASTPIN (0 -825) $PN 2
J 0
(10 -845);
DISPLAY 0.787234 (10 -845);
PAINT MONO (10 -845);
FORCEPROP 1 LAST PATH I162
J 0
(50 -575);
DISPLAY 0.978723 (50 -575);
PAINT WHITE (50 -575);
DISPLAY INVISIBLE (50 -575);
FORCEPROP 2 LAST CDS_LIB pure_quanta
J 0
(0 -725);
DISPLAY INVISIBLE (0 -725);
FORCEPROP 0 LAST $SEC 1
J 0
(50 -575);
DISPLAY 0.680851 (50 -575);
PAINT MONO (50 -575);
DISPLAY INVISIBLE (50 -575);
FORCEPROP 0 LAST CDS_SEC 1
J 0
(50 -575);
DISPLAY 1.021277 (50 -575);
DISPLAY INVISIBLE (50 -575);
FORCEADD Q_CAP..1
(450 -725);
FORCEPROP 1 LAST PART_NUMBER CH6471MEA02
J 0
(500 -875);
DISPLAY 0.638298 (500 -875);
DISPLAY INVISIBLE (500 -875);
FORCEPROP 1 LAST VOLTAGE 6.3V
J 0
(500 -725);
DISPLAY 0.638298 (500 -725);
FORCEPROP 1 LAST VALUE 47UF
J 0
(500 -675);
DISPLAY 0.638298 (500 -675);
FORCEPROP 1 LAST TOLERANCE 20%
J 0
(500 -775);
DISPLAY 0.638298 (500 -775);
FORCEPROP 1 LAST MATERIAL X6S
J 0
(500 -825);
DISPLAY 0.638298 (500 -825);
FORCEPROP 1 LAST PACK_TYPE C0805
J 0
(500 -925);
DISPLAY 0.638298 (500 -925);
FORCEPROP 1 LAST LOCATION C1245
J 0
(500 -625);
DISPLAY 0.638298 (500 -625);
FORCEPROP 1 LASTPIN (450 -625) $PN 1
J 0
(460 -645);
DISPLAY 0.787234 (460 -645);
PAINT MONO (460 -645);
FORCEPROP 1 LASTPIN (450 -825) $PN 2
J 0
(460 -845);
DISPLAY 0.787234 (460 -845);
PAINT MONO (460 -845);
FORCEPROP 1 LAST PATH I163
J 0
(500 -575);
DISPLAY 0.978723 (500 -575);
PAINT WHITE (500 -575);
DISPLAY INVISIBLE (500 -575);
FORCEPROP 2 LAST CDS_LIB pure_quanta
J 0
(450 -725);
DISPLAY INVISIBLE (450 -725);
FORCEPROP 0 LAST $SEC 1
J 0
(500 -575);
DISPLAY 0.680851 (500 -575);
PAINT MONO (500 -575);
DISPLAY INVISIBLE (500 -575);
FORCEPROP 0 LAST CDS_SEC 1
J 0
(500 -575);
DISPLAY 1.021277 (500 -575);
DISPLAY INVISIBLE (500 -575);
FORCEADD Q_INDUCTOR..1
(2700 3775);
FORCEPROP 1 LAST PART_NUMBER CX5PX121001
J 0
(2575 3885);
DISPLAY 0.574468 (2575 3885);
PAINT GREEN (2575 3885);
DISPLAY INVISIBLE (2575 3885);
FORCEPROP 1 LAST MATERIAL EMPTY
J 0
(2575 3830);
DISPLAY 0.574468 (2575 3830);
PAINT GREEN (2575 3830);
FORCEPROP 2 LAST PACK_TYPE SMLF
J 0
(2425 3825);
DISPLAY 0.808511 (2425 3825);
FORCEPROP 2 LAST VALUE BLM15PX121SN1D/2A
J 0
(2725 3825);
DISPLAY 0.808511 (2725 3825);
FORCEPROP 1 LAST LOCATION L2
J 0
(2500 3875);
DISPLAY 0.723404 (2500 3875);
PAINT GREEN (2500 3875);
FORCEPROP 0 LASTPIN (2600 3750) $PN 1
J 2
(2590 3760);
DISPLAY 0.680851 (2590 3760);
PAINT MONO (2590 3760);
FORCEPROP 0 LASTPIN (2800 3750) $PN 2
J 0
(2810 3760);
DISPLAY 0.680851 (2810 3760);
PAINT MONO (2810 3760);
FORCEPROP 1 LAST NEEDS_NO_SIZE TRUE
J 0
(2700 3775);
DISPLAY 0.468085 (2700 3775);
PAINT GREEN (2700 3775);
DISPLAY INVISIBLE (2700 3775);
FORCEPROP 1 LAST PATH I164
J 0
(2775 3830);
DISPLAY 0.723404 (2775 3830);
PAINT GREEN (2775 3830);
DISPLAY INVISIBLE (2775 3830);
FORCEPROP 2 LAST CDS_LIB pure_quanta
J 0
(2700 3775);
DISPLAY INVISIBLE (2700 3775);
FORCEPROP 0 LAST $SEC 1
J 0
(2575 3925);
DISPLAY 0.680851 (2575 3925);
PAINT MONO (2575 3925);
DISPLAY INVISIBLE (2575 3925);
FORCEPROP 0 LAST CDS_SEC 1
J 0
(2575 3925);
DISPLAY 1.021277 (2575 3925);
DISPLAY INVISIBLE (2575 3925);
FORCEADD Q_RES..1
(3150 4125);
FORCEPROP 1 LAST PART_NUMBER CS00002JB13
J 0
(3050 4200);
DISPLAY 0.404255 (3050 4200);
DISPLAY INVISIBLE (3050 4200);
FORCEPROP 1 LAST TOLERANCE 5%
J 0
(3325 4125);
DISPLAY 0.510638 (3325 4125);
FORCEPROP 1 LAST VALUE 0
J 2
(3300 4125);
DISPLAY 0.510638 (3300 4125);
FORCEPROP 1 LAST WATTAGE 1/16W
J 2
(3300 4250);
DISPLAY 0.404255 (3300 4250);
FORCEPROP 1 LAST PACK_TYPE 0402LF
J 0
(3050 4250);
DISPLAY 0.404255 (3050 4250);
FORCEPROP 1 LAST MATERIAL CHIP
J 0
(3400 4125);
DISPLAY 0.510638 (3400 4125);
FORCEPROP 1 LAST $LOCATION R4803
J 0
(2925 4125);
DISPLAY 0.638298 (2925 4125);
FORCEPROP 1 LASTPIN (3050 4125) $PN 1
J 0
(3062 4137);
DISPLAY 0.787234 (3062 4137);
PAINT MONO (3062 4137);
FORCEPROP 1 LASTPIN (3250 4125) $PN 2
J 0
(3212 4137);
DISPLAY 0.787234 (3212 4137);
PAINT MONO (3212 4137);
FORCEPROP 1 LAST PATH I165
J 0
(3100 4275);
DISPLAY 0.978723 (3100 4275);
PAINT WHITE (3100 4275);
DISPLAY INVISIBLE (3100 4275);
FORCEPROP 2 LAST CDS_LIB pure_quanta
J 0
(3150 4125);
DISPLAY INVISIBLE (3150 4125);
FORCEPROP 0 LAST CDS_LOCATION R4803
J 0
(3300 4275);
DISPLAY 1.021277 (3300 4275);
DISPLAY INVISIBLE (3300 4275);
FORCEPROP 0 LAST $SEC 1
J 0
(3300 4275);
DISPLAY 0.680851 (3300 4275);
PAINT MONO (3300 4275);
DISPLAY INVISIBLE (3300 4275);
FORCEPROP 0 LAST CDS_SEC 1
J 0
(3300 4275);
DISPLAY 1.021277 (3300 4275);
DISPLAY INVISIBLE (3300 4275);
FORCEADD UNIVERSAL_GND..1
(950 3475);
FORCEPROP 3 LASTPIN (950 3525) SIG_NAME GND\g
J 0
(960 3535);
DISPLAY 0.659574 (960 3535);
PAINT MONO (960 3535);
DISPLAY INVISIBLE (960 3535);
FORCEPROP 2 LAST ROOM IO_SLOT
J 1
(725 3550);
DISPLAY 0.744681 (725 3550);
DISPLAY INVISIBLE (725 3550);
FORCEPROP 1 LAST PATH I18
J 0
(1025 3475);
DISPLAY 0.872340 (1025 3475);
PAINT AQUA (1025 3475);
DISPLAY INVISIBLE (1025 3475);
FORCEPROP 1 LAST HDL_POWER GND
J 1
(975 3400);
DISPLAY 0.872340 (975 3400);
PAINT GREEN (975 3400);
DISPLAY INVISIBLE (975 3400);
FORCEPROP 2 LAST CDS_LIB logical_power
J 0
(950 3475);
PAINT MONO (950 3475);
DISPLAY INVISIBLE (950 3475);
FORCEADD UNIVERSAL_POWER..1
(50 4100);
FORCEPROP 3 LASTPIN (50 4050) SIG_NAME P1V05_PCH_AUX\g
J 0
(60 4060);
DISPLAY 0.659574 (60 4060);
PAINT MONO (60 4060);
DISPLAY INVISIBLE (60 4060);
FORCEPROP 1 LAST HDL_POWER P1V05_PCH_AUX
J 1
(50 4150);
DISPLAY 0.872340 (50 4150);
PAINT GREEN (50 4150);
FORCEPROP 1 LAST PATH I20
J 0
(100 4125);
DISPLAY 0.872340 (100 4125);
PAINT AQUA (100 4125);
DISPLAY INVISIBLE (100 4125);
FORCEPROP 2 LAST CDS_LIB logical_power
J 0
(50 4100);
DISPLAY INVISIBLE (50 4100);
FORCEADD Q_CAP..1
(-1800 2500);
FORCEPROP 1 LAST PART_NUMBER CH622KME901
J 0
(-1750 2350);
DISPLAY 0.638298 (-1750 2350);
DISPLAY INVISIBLE (-1750 2350);
FORCEPROP 1 LAST VOLTAGE 4V
J 0
(-1750 2500);
DISPLAY 0.638298 (-1750 2500);
FORCEPROP 1 LAST TOLERANCE 20%
J 0
(-1750 2450);
DISPLAY 0.638298 (-1750 2450);
FORCEPROP 1 LAST MATERIAL X6S
J 0
(-1750 2400);
DISPLAY 0.638298 (-1750 2400);
FORCEPROP 1 LAST PACK_TYPE C0603
J 0
(-1750 2300);
DISPLAY 0.638298 (-1750 2300);
FORCEPROP 1 LAST VALUE 22UF
J 0
(-1750 2550);
DISPLAY 0.638298 (-1750 2550);
FORCEPROP 1 LAST $LOCATION C1186
J 0
(-1750 2600);
DISPLAY 0.638298 (-1750 2600);
FORCEPROP 1 LASTPIN (-1800 2600) $PN 1
J 0
(-1790 2580);
DISPLAY 0.787234 (-1790 2580);
FORCEPROP 1 LASTPIN (-1800 2400) $PN 2
J 0
(-1790 2380);
DISPLAY 0.787234 (-1790 2380);
FORCEPROP 1 LAST PATH I25
J 0
(-1750 2650);
DISPLAY 0.978723 (-1750 2650);
PAINT WHITE (-1750 2650);
DISPLAY INVISIBLE (-1750 2650);
FORCEPROP 2 LAST CDS_LIB pure_quanta
J 0
(-1800 2500);
PAINT MONO (-1800 2500);
DISPLAY INVISIBLE (-1800 2500);
FORCEPROP 2 LAST CDS_LOCATION C1186
J 0
(-1750 2700);
DISPLAY 1.021277 (-1750 2700);
DISPLAY INVISIBLE (-1750 2700);
FORCEPROP 2 LAST $SEC 1
J 0
(-1750 2700);
DISPLAY 0.680851 (-1750 2700);
PAINT MONO (-1750 2700);
DISPLAY INVISIBLE (-1750 2700);
FORCEPROP 2 LAST CDS_SEC 1
J 0
(-1750 2700);
DISPLAY 1.021277 (-1750 2700);
DISPLAY INVISIBLE (-1750 2700);
FORCEADD UNIVERSAL_POWER..1
(-2250 2775);
FORCEPROP 3 LASTPIN (-2250 2725) SIG_NAME P1V8_PCH_AUX\g
J 0
(-2240 2735);
DISPLAY 0.659574 (-2240 2735);
PAINT MONO (-2240 2735);
DISPLAY INVISIBLE (-2240 2735);
FORCEPROP 1 LAST HDL_POWER P1V8_PCH_AUX
J 1
(-2250 2825);
DISPLAY 0.872340 (-2250 2825);
PAINT GREEN (-2250 2825);
FORCEPROP 1 LAST PATH I26
J 0
(-2200 2800);
DISPLAY 0.872340 (-2200 2800);
PAINT AQUA (-2200 2800);
DISPLAY INVISIBLE (-2200 2800);
FORCEPROP 2 LAST CDS_LIB logical_power
J 0
(-2250 2775);
DISPLAY INVISIBLE (-2250 2775);
FORCEADD Q_CAP..1
(-2250 2500);
FORCEPROP 1 LAST PART_NUMBER CH622KME901
J 0
(-2200 2350);
DISPLAY 0.638298 (-2200 2350);
DISPLAY INVISIBLE (-2200 2350);
FORCEPROP 1 LAST TOLERANCE 20%
J 0
(-2200 2450);
DISPLAY 0.638298 (-2200 2450);
FORCEPROP 1 LAST VOLTAGE 4V
J 0
(-2200 2500);
DISPLAY 0.638298 (-2200 2500);
FORCEPROP 1 LAST PACK_TYPE C0603
J 0
(-2200 2300);
DISPLAY 0.638298 (-2200 2300);
FORCEPROP 1 LAST VALUE 22UF
J 0
(-2200 2550);
DISPLAY 0.638298 (-2200 2550);
FORCEPROP 1 LAST MATERIAL X6S
J 0
(-2200 2400);
DISPLAY 0.638298 (-2200 2400);
FORCEPROP 1 LAST $LOCATION C1181
J 0
(-2200 2600);
DISPLAY 0.638298 (-2200 2600);
FORCEPROP 1 LASTPIN (-2250 2600) $PN 1
J 0
(-2240 2580);
DISPLAY 0.787234 (-2240 2580);
FORCEPROP 1 LASTPIN (-2250 2400) $PN 2
J 0
(-2240 2380);
DISPLAY 0.787234 (-2240 2380);
FORCEPROP 1 LAST PATH I27
J 0
(-2200 2650);
DISPLAY 0.978723 (-2200 2650);
PAINT WHITE (-2200 2650);
DISPLAY INVISIBLE (-2200 2650);
FORCEPROP 2 LAST CDS_LIB pure_quanta
J 0
(-2250 2500);
PAINT MONO (-2250 2500);
DISPLAY INVISIBLE (-2250 2500);
FORCEPROP 2 LAST CDS_LOCATION C1181
J 0
(-2200 2700);
DISPLAY 1.021277 (-2200 2700);
DISPLAY INVISIBLE (-2200 2700);
FORCEPROP 2 LAST $SEC 1
J 0
(-2200 2700);
DISPLAY 0.680851 (-2200 2700);
PAINT MONO (-2200 2700);
DISPLAY INVISIBLE (-2200 2700);
FORCEPROP 2 LAST CDS_SEC 1
J 0
(-2200 2700);
DISPLAY 1.021277 (-2200 2700);
DISPLAY INVISIBLE (-2200 2700);
FORCEADD UNIVERSAL_GND..1
(-900 2150);
FORCEPROP 3 LASTPIN (-900 2200) SIG_NAME GND\g
J 0
(-890 2210);
DISPLAY 0.659574 (-890 2210);
PAINT MONO (-890 2210);
DISPLAY INVISIBLE (-890 2210);
FORCEPROP 2 LAST ROOM IO_SLOT
J 1
(-1125 2225);
DISPLAY 0.744681 (-1125 2225);
DISPLAY INVISIBLE (-1125 2225);
FORCEPROP 1 LAST PATH I28
J 0
(-825 2150);
DISPLAY 0.872340 (-825 2150);
PAINT AQUA (-825 2150);
DISPLAY INVISIBLE (-825 2150);
FORCEPROP 1 LAST HDL_POWER GND
J 1
(-875 2075);
DISPLAY 0.872340 (-875 2075);
PAINT GREEN (-875 2075);
DISPLAY INVISIBLE (-875 2075);
FORCEPROP 2 LAST CDS_LIB logical_power
J 0
(-900 2150);
PAINT MONO (-900 2150);
DISPLAY INVISIBLE (-900 2150);
FORCEADD Q_CAP..1
(-900 2500);
FORCEPROP 1 LAST PART_NUMBER CH622KME901
J 0
(-850 2350);
DISPLAY 0.638298 (-850 2350);
DISPLAY INVISIBLE (-850 2350);
FORCEPROP 1 LAST VOLTAGE 4V
J 0
(-850 2500);
DISPLAY 0.638298 (-850 2500);
FORCEPROP 1 LAST VALUE 22UF
J 0
(-850 2550);
DISPLAY 0.638298 (-850 2550);
FORCEPROP 1 LAST TOLERANCE 20%
J 0
(-850 2450);
DISPLAY 0.638298 (-850 2450);
FORCEPROP 1 LAST MATERIAL X6S
J 0
(-850 2400);
DISPLAY 0.638298 (-850 2400);
FORCEPROP 1 LAST PACK_TYPE C0603
J 0
(-850 2300);
DISPLAY 0.638298 (-850 2300);
FORCEPROP 1 LAST $LOCATION C1202
J 0
(-850 2600);
DISPLAY 0.638298 (-850 2600);
FORCEPROP 1 LASTPIN (-900 2600) $PN 1
J 0
(-890 2580);
DISPLAY 0.787234 (-890 2580);
FORCEPROP 1 LASTPIN (-900 2400) $PN 2
J 0
(-890 2380);
DISPLAY 0.787234 (-890 2380);
FORCEPROP 1 LAST PATH I29
J 0
(-850 2650);
DISPLAY 0.978723 (-850 2650);
PAINT WHITE (-850 2650);
DISPLAY INVISIBLE (-850 2650);
FORCEPROP 2 LAST CDS_LIB pure_quanta
J 0
(-900 2500);
PAINT MONO (-900 2500);
DISPLAY INVISIBLE (-900 2500);
FORCEPROP 2 LAST CDS_LOCATION C1202
J 0
(-850 2700);
DISPLAY 1.021277 (-850 2700);
DISPLAY INVISIBLE (-850 2700);
FORCEPROP 2 LAST $SEC 1
J 0
(-850 2700);
DISPLAY 0.680851 (-850 2700);
PAINT MONO (-850 2700);
DISPLAY INVISIBLE (-850 2700);
FORCEPROP 2 LAST CDS_SEC 1
J 0
(-850 2700);
DISPLAY 1.021277 (-850 2700);
DISPLAY INVISIBLE (-850 2700);
FORCEADD Q_CAP..1
(-1350 2500);
FORCEPROP 1 LAST PART_NUMBER CH622KME901
J 0
(-1300 2350);
DISPLAY 0.638298 (-1300 2350);
DISPLAY INVISIBLE (-1300 2350);
FORCEPROP 1 LAST MATERIAL X6S
J 0
(-1300 2400);
DISPLAY 0.638298 (-1300 2400);
FORCEPROP 1 LAST TOLERANCE 20%
J 0
(-1300 2450);
DISPLAY 0.638298 (-1300 2450);
FORCEPROP 1 LAST VOLTAGE 4V
J 0
(-1300 2500);
DISPLAY 0.638298 (-1300 2500);
FORCEPROP 1 LAST VALUE 22UF
J 0
(-1300 2550);
DISPLAY 0.638298 (-1300 2550);
FORCEPROP 1 LAST PACK_TYPE C0603
J 0
(-1300 2300);
DISPLAY 0.638298 (-1300 2300);
FORCEPROP 1 LAST $LOCATION C1197
J 0
(-1300 2600);
DISPLAY 0.638298 (-1300 2600);
FORCEPROP 1 LASTPIN (-1350 2600) $PN 1
J 0
(-1340 2580);
DISPLAY 0.787234 (-1340 2580);
FORCEPROP 1 LASTPIN (-1350 2400) $PN 2
J 0
(-1340 2380);
DISPLAY 0.787234 (-1340 2380);
FORCEPROP 1 LAST PATH I30
J 0
(-1300 2650);
DISPLAY 0.978723 (-1300 2650);
PAINT WHITE (-1300 2650);
DISPLAY INVISIBLE (-1300 2650);
FORCEPROP 2 LAST CDS_LIB pure_quanta
J 0
(-1350 2500);
PAINT MONO (-1350 2500);
DISPLAY INVISIBLE (-1350 2500);
FORCEPROP 2 LAST CDS_LOCATION C1197
J 0
(-1300 2700);
DISPLAY 1.021277 (-1300 2700);
DISPLAY INVISIBLE (-1300 2700);
FORCEPROP 2 LAST $SEC 1
J 0
(-1300 2700);
DISPLAY 0.680851 (-1300 2700);
PAINT MONO (-1300 2700);
DISPLAY INVISIBLE (-1300 2700);
FORCEPROP 2 LAST CDS_SEC 1
J 0
(-1300 2700);
DISPLAY 1.021277 (-1300 2700);
DISPLAY INVISIBLE (-1300 2700);
FORCEADD UNIVERSAL_POWER..1
(-450 2775);
FORCEPROP 3 LASTPIN (-450 2725) SIG_NAME P1V8_PCH_AUX\g
J 0
(-440 2735);
DISPLAY 0.659574 (-440 2735);
PAINT MONO (-440 2735);
DISPLAY INVISIBLE (-440 2735);
FORCEPROP 1 LAST HDL_POWER P1V8_PCH_AUX
J 1
(-450 2825);
DISPLAY 0.872340 (-450 2825);
PAINT GREEN (-450 2825);
FORCEPROP 1 LAST PATH I31
J 0
(-400 2800);
DISPLAY 0.872340 (-400 2800);
PAINT AQUA (-400 2800);
DISPLAY INVISIBLE (-400 2800);
FORCEPROP 2 LAST CDS_LIB logical_power
J 0
(-450 2775);
PAINT MONO (-450 2775);
DISPLAY INVISIBLE (-450 2775);
FORCEADD Q_CAP..1
(-450 2500);
FORCEPROP 1 LAST PART_NUMBER CH6101MEB01
J 0
(-400 2350);
DISPLAY 0.638298 (-400 2350);
DISPLAY INVISIBLE (-400 2350);
FORCEPROP 1 LAST PACK_TYPE C0402
J 0
(-400 2300);
DISPLAY 0.638298 (-400 2300);
FORCEPROP 1 LAST VALUE 10UF
J 0
(-400 2550);
DISPLAY 0.638298 (-400 2550);
FORCEPROP 1 LAST MATERIAL X6S
J 0
(-400 2400);
DISPLAY 0.638298 (-400 2400);
FORCEPROP 1 LAST TOLERANCE 20%
J 0
(-400 2450);
DISPLAY 0.638298 (-400 2450);
FORCEPROP 1 LAST VOLTAGE 6.3V
J 0
(-400 2500);
DISPLAY 0.638298 (-400 2500);
FORCEPROP 1 LAST $LOCATION C1207
J 0
(-400 2600);
DISPLAY 0.978723 (-400 2600);
FORCEPROP 1 LASTPIN (-450 2600) $PN 1
J 0
(-440 2580);
DISPLAY 0.787234 (-440 2580);
FORCEPROP 1 LASTPIN (-450 2400) $PN 2
J 0
(-440 2380);
DISPLAY 0.787234 (-440 2380);
FORCEPROP 1 LAST PATH I32
J 0
(-400 2650);
DISPLAY 0.978723 (-400 2650);
PAINT WHITE (-400 2650);
DISPLAY INVISIBLE (-400 2650);
FORCEPROP 2 LAST CDS_LIB pure_quanta
J 0
(-450 2500);
PAINT MONO (-450 2500);
DISPLAY INVISIBLE (-450 2500);
FORCEPROP 2 LAST CDS_LOCATION C1207
J 0
(-400 2700);
DISPLAY 1.021277 (-400 2700);
DISPLAY INVISIBLE (-400 2700);
FORCEPROP 2 LAST $SEC 1
J 0
(-400 2700);
DISPLAY 0.680851 (-400 2700);
PAINT MONO (-400 2700);
DISPLAY INVISIBLE (-400 2700);
FORCEPROP 2 LAST CDS_SEC 1
J 0
(-400 2700);
DISPLAY 1.021277 (-400 2700);
DISPLAY INVISIBLE (-400 2700);
FORCEADD UNIVERSAL_GND..1
(-450 2150);
FORCEPROP 3 LASTPIN (-450 2200) SIG_NAME GND\g
J 0
(-440 2210);
DISPLAY 0.659574 (-440 2210);
PAINT MONO (-440 2210);
DISPLAY INVISIBLE (-440 2210);
FORCEPROP 2 LAST ROOM IO_SLOT
J 1
(-675 2225);
DISPLAY 0.744681 (-675 2225);
DISPLAY INVISIBLE (-675 2225);
FORCEPROP 1 LAST PATH I33
J 0
(-375 2150);
DISPLAY 0.872340 (-375 2150);
PAINT AQUA (-375 2150);
DISPLAY INVISIBLE (-375 2150);
FORCEPROP 1 LAST HDL_POWER GND
J 1
(-425 2075);
DISPLAY 0.872340 (-425 2075);
PAINT GREEN (-425 2075);
DISPLAY INVISIBLE (-425 2075);
FORCEPROP 2 LAST CDS_LIB logical_power
J 0
(-450 2150);
PAINT MONO (-450 2150);
DISPLAY INVISIBLE (-450 2150);
FORCEADD UNIVERSAL_POWER..1
(-2250 4100);
FORCEPROP 3 LASTPIN (-2250 4050) SIG_NAME P1V05_PCH_AUX\g
J 0
(-2240 4060);
DISPLAY 0.659574 (-2240 4060);
PAINT MONO (-2240 4060);
DISPLAY INVISIBLE (-2240 4060);
FORCEPROP 1 LAST HDL_POWER P1V05_PCH_AUX
J 1
(-2250 4150);
DISPLAY 0.872340 (-2250 4150);
PAINT GREEN (-2250 4150);
FORCEPROP 1 LAST PATH I4
J 0
(-2200 4125);
DISPLAY 0.872340 (-2200 4125);
PAINT AQUA (-2200 4125);
DISPLAY INVISIBLE (-2200 4125);
FORCEPROP 2 LAST CDS_LIB logical_power
J 0
(-2250 4100);
DISPLAY INVISIBLE (-2250 4100);
FORCEADD Q_CAP..1
(-1800 1200);
FORCEPROP 1 LAST PART_NUMBER CH622KME901
J 0
(-1750 1050);
DISPLAY 0.638298 (-1750 1050);
DISPLAY INVISIBLE (-1750 1050);
FORCEPROP 1 LAST VOLTAGE 4V
J 0
(-1750 1200);
DISPLAY 0.638298 (-1750 1200);
FORCEPROP 1 LAST VALUE 22UF
J 0
(-1750 1250);
DISPLAY 0.638298 (-1750 1250);
FORCEPROP 1 LAST PACK_TYPE C0603
J 0
(-1750 1000);
DISPLAY 0.638298 (-1750 1000);
FORCEPROP 1 LAST MATERIAL X6S
J 0
(-1750 1100);
DISPLAY 0.638298 (-1750 1100);
FORCEPROP 1 LAST TOLERANCE 20%
J 0
(-1750 1150);
DISPLAY 0.638298 (-1750 1150);
FORCEPROP 1 LAST $LOCATION C1187
J 0
(-1750 1300);
DISPLAY 0.638298 (-1750 1300);
FORCEPROP 1 LASTPIN (-1800 1300) $PN 1
J 0
(-1790 1280);
DISPLAY 0.787234 (-1790 1280);
FORCEPROP 1 LASTPIN (-1800 1100) $PN 2
J 0
(-1790 1080);
DISPLAY 0.787234 (-1790 1080);
FORCEPROP 1 LAST PATH I40
J 0
(-1750 1350);
DISPLAY 0.978723 (-1750 1350);
PAINT WHITE (-1750 1350);
DISPLAY INVISIBLE (-1750 1350);
FORCEPROP 2 LAST CDS_LIB pure_quanta
J 0
(-1800 1200);
PAINT MONO (-1800 1200);
DISPLAY INVISIBLE (-1800 1200);
FORCEPROP 2 LAST CDS_LOCATION C1187
J 0
(-1750 1400);
DISPLAY 1.021277 (-1750 1400);
DISPLAY INVISIBLE (-1750 1400);
FORCEPROP 2 LAST $SEC 1
J 0
(-1750 1400);
DISPLAY 0.680851 (-1750 1400);
PAINT MONO (-1750 1400);
DISPLAY INVISIBLE (-1750 1400);
FORCEPROP 2 LAST CDS_SEC 1
J 0
(-1750 1400);
DISPLAY 1.021277 (-1750 1400);
DISPLAY INVISIBLE (-1750 1400);
FORCEADD UNIVERSAL_POWER..1
(-2250 1475);
FORCEPROP 3 LASTPIN (-2250 1425) SIG_NAME P1V05_PCH_AUX\g
J 0
(-2240 1435);
DISPLAY 0.659574 (-2240 1435);
PAINT MONO (-2240 1435);
DISPLAY INVISIBLE (-2240 1435);
FORCEPROP 1 LAST HDL_POWER P1V05_PCH_AUX
J 1
(-2250 1525);
DISPLAY 0.872340 (-2250 1525);
PAINT GREEN (-2250 1525);
FORCEPROP 1 LAST PATH I41
J 0
(-2200 1500);
DISPLAY 0.872340 (-2200 1500);
PAINT AQUA (-2200 1500);
DISPLAY INVISIBLE (-2200 1500);
FORCEPROP 2 LAST CDS_LIB logical_power
J 0
(-2250 1475);
DISPLAY INVISIBLE (-2250 1475);
FORCEADD Q_CAP..1
(-2250 1200);
FORCEPROP 1 LAST PART_NUMBER CH622KME901
J 0
(-2200 1050);
DISPLAY 0.638298 (-2200 1050);
DISPLAY INVISIBLE (-2200 1050);
FORCEPROP 1 LAST VOLTAGE 4V
J 0
(-2200 1200);
DISPLAY 0.638298 (-2200 1200);
FORCEPROP 1 LAST TOLERANCE 20%
J 0
(-2200 1150);
DISPLAY 0.638298 (-2200 1150);
FORCEPROP 1 LAST VALUE 22UF
J 0
(-2200 1250);
DISPLAY 0.638298 (-2200 1250);
FORCEPROP 1 LAST MATERIAL X6S
J 0
(-2200 1100);
DISPLAY 0.638298 (-2200 1100);
FORCEPROP 1 LAST PACK_TYPE C0603
J 0
(-2200 1000);
DISPLAY 0.638298 (-2200 1000);
FORCEPROP 1 LAST $LOCATION C1182
J 0
(-2200 1300);
DISPLAY 0.638298 (-2200 1300);
FORCEPROP 1 LASTPIN (-2250 1300) $PN 1
J 0
(-2240 1280);
DISPLAY 0.787234 (-2240 1280);
FORCEPROP 1 LASTPIN (-2250 1100) $PN 2
J 0
(-2240 1080);
DISPLAY 0.787234 (-2240 1080);
FORCEPROP 1 LAST PATH I42
J 0
(-2200 1350);
DISPLAY 0.978723 (-2200 1350);
PAINT WHITE (-2200 1350);
DISPLAY INVISIBLE (-2200 1350);
FORCEPROP 2 LAST CDS_LIB pure_quanta
J 0
(-2250 1200);
PAINT MONO (-2250 1200);
DISPLAY INVISIBLE (-2250 1200);
FORCEPROP 2 LAST CDS_LOCATION C1182
J 0
(-2200 1400);
DISPLAY 1.021277 (-2200 1400);
DISPLAY INVISIBLE (-2200 1400);
FORCEPROP 2 LAST $SEC 1
J 0
(-2200 1400);
DISPLAY 0.680851 (-2200 1400);
PAINT MONO (-2200 1400);
DISPLAY INVISIBLE (-2200 1400);
FORCEPROP 2 LAST CDS_SEC 1
J 0
(-2200 1400);
DISPLAY 1.021277 (-2200 1400);
DISPLAY INVISIBLE (-2200 1400);
FORCEADD Q_CAP..1
(-1350 1200);
FORCEPROP 1 LAST PART_NUMBER CH622KME901
J 0
(-1300 1050);
DISPLAY 0.638298 (-1300 1050);
DISPLAY INVISIBLE (-1300 1050);
FORCEPROP 1 LAST VALUE 22UF
J 0
(-1300 1250);
DISPLAY 0.638298 (-1300 1250);
FORCEPROP 1 LAST MATERIAL X6S
J 0
(-1300 1100);
DISPLAY 0.638298 (-1300 1100);
FORCEPROP 1 LAST TOLERANCE 20%
J 0
(-1300 1150);
DISPLAY 0.638298 (-1300 1150);
FORCEPROP 1 LAST PACK_TYPE C0603
J 0
(-1300 1000);
DISPLAY 0.638298 (-1300 1000);
FORCEPROP 1 LAST VOLTAGE 4V
J 0
(-1300 1200);
DISPLAY 0.638298 (-1300 1200);
FORCEPROP 1 LAST $LOCATION C1198
J 0
(-1300 1300);
DISPLAY 0.638298 (-1300 1300);
FORCEPROP 1 LASTPIN (-1350 1300) $PN 1
J 0
(-1340 1280);
DISPLAY 0.787234 (-1340 1280);
FORCEPROP 1 LASTPIN (-1350 1100) $PN 2
J 0
(-1340 1080);
DISPLAY 0.787234 (-1340 1080);
FORCEPROP 1 LAST PATH I43
J 0
(-1300 1350);
DISPLAY 0.978723 (-1300 1350);
PAINT WHITE (-1300 1350);
DISPLAY INVISIBLE (-1300 1350);
FORCEPROP 2 LAST CDS_LIB pure_quanta
J 0
(-1350 1200);
PAINT MONO (-1350 1200);
DISPLAY INVISIBLE (-1350 1200);
FORCEPROP 2 LAST CDS_LOCATION C1198
J 0
(-1300 1400);
DISPLAY 1.021277 (-1300 1400);
DISPLAY INVISIBLE (-1300 1400);
FORCEPROP 2 LAST $SEC 1
J 0
(-1300 1400);
DISPLAY 0.680851 (-1300 1400);
PAINT MONO (-1300 1400);
DISPLAY INVISIBLE (-1300 1400);
FORCEPROP 2 LAST CDS_SEC 1
J 0
(-1300 1400);
DISPLAY 1.021277 (-1300 1400);
DISPLAY INVISIBLE (-1300 1400);
FORCEADD UNIVERSAL_GND..1
(-1350 850);
FORCEPROP 3 LASTPIN (-1350 900) SIG_NAME GND\g
J 0
(-1340 910);
DISPLAY 0.659574 (-1340 910);
PAINT MONO (-1340 910);
DISPLAY INVISIBLE (-1340 910);
FORCEPROP 2 LAST ROOM IO_SLOT
J 1
(-1575 925);
DISPLAY 0.744681 (-1575 925);
DISPLAY INVISIBLE (-1575 925);
FORCEPROP 1 LAST PATH I44
J 0
(-1275 850);
DISPLAY 0.872340 (-1275 850);
PAINT AQUA (-1275 850);
DISPLAY INVISIBLE (-1275 850);
FORCEPROP 1 LAST HDL_POWER GND
J 1
(-1325 775);
DISPLAY 0.872340 (-1325 775);
PAINT GREEN (-1325 775);
DISPLAY INVISIBLE (-1325 775);
FORCEPROP 2 LAST CDS_LIB logical_power
J 0
(-1350 850);
PAINT MONO (-1350 850);
DISPLAY INVISIBLE (-1350 850);
FORCEADD Q_CAP..1
(-450 1200);
FORCEPROP 1 LAST PART_NUMBER CH6101MEB01
J 0
(-400 1050);
DISPLAY 0.638298 (-400 1050);
DISPLAY INVISIBLE (-400 1050);
FORCEPROP 1 LAST MATERIAL X6S
J 0
(-400 1100);
DISPLAY 0.638298 (-400 1100);
FORCEPROP 1 LAST TOLERANCE 20%
J 0
(-400 1150);
DISPLAY 0.638298 (-400 1150);
FORCEPROP 1 LAST VALUE 10UF
J 0
(-400 1250);
DISPLAY 0.638298 (-400 1250);
FORCEPROP 1 LAST VOLTAGE 6.3V
J 0
(-400 1200);
DISPLAY 0.638298 (-400 1200);
FORCEPROP 1 LAST PACK_TYPE C0402
J 0
(-400 1000);
DISPLAY 0.638298 (-400 1000);
FORCEPROP 1 LAST $LOCATION C1210
J 0
(-400 1300);
DISPLAY 0.638298 (-400 1300);
FORCEPROP 1 LASTPIN (-450 1300) $PN 1
J 0
(-440 1280);
DISPLAY 0.787234 (-440 1280);
FORCEPROP 1 LASTPIN (-450 1100) $PN 2
J 0
(-440 1080);
DISPLAY 0.787234 (-440 1080);
FORCEPROP 1 LAST PATH I45
J 0
(-400 1350);
DISPLAY 0.978723 (-400 1350);
PAINT WHITE (-400 1350);
DISPLAY INVISIBLE (-400 1350);
FORCEPROP 2 LAST CDS_LIB pure_quanta
J 0
(-450 1200);
PAINT MONO (-450 1200);
DISPLAY INVISIBLE (-450 1200);
FORCEPROP 2 LAST CDS_LOCATION C1210
J 0
(-400 1400);
DISPLAY 1.021277 (-400 1400);
DISPLAY INVISIBLE (-400 1400);
FORCEPROP 2 LAST $SEC 1
J 0
(-400 1400);
DISPLAY 0.680851 (-400 1400);
PAINT MONO (-400 1400);
DISPLAY INVISIBLE (-400 1400);
FORCEPROP 2 LAST CDS_SEC 1
J 0
(-400 1400);
DISPLAY 1.021277 (-400 1400);
DISPLAY INVISIBLE (-400 1400);
FORCEADD Q_CAP..1
(-900 1200);
FORCEPROP 1 LAST PART_NUMBER CH6101MEB01
J 0
(-850 1050);
DISPLAY 0.638298 (-850 1050);
DISPLAY INVISIBLE (-850 1050);
FORCEPROP 1 LAST PACK_TYPE C0402
J 0
(-850 1000);
DISPLAY 0.638298 (-850 1000);
FORCEPROP 1 LAST MATERIAL X6S
J 0
(-850 1100);
DISPLAY 0.638298 (-850 1100);
FORCEPROP 1 LAST VOLTAGE 6.3V
J 0
(-850 1200);
DISPLAY 0.638298 (-850 1200);
FORCEPROP 1 LAST TOLERANCE 20%
J 0
(-850 1150);
DISPLAY 0.638298 (-850 1150);
FORCEPROP 1 LAST VALUE 10UF
J 0
(-850 1250);
DISPLAY 0.638298 (-850 1250);
FORCEPROP 1 LAST $LOCATION C1203
J 0
(-850 1300);
DISPLAY 0.638298 (-850 1300);
FORCEPROP 1 LASTPIN (-900 1300) $PN 1
J 0
(-890 1280);
DISPLAY 0.787234 (-890 1280);
FORCEPROP 1 LASTPIN (-900 1100) $PN 2
J 0
(-890 1080);
DISPLAY 0.787234 (-890 1080);
FORCEPROP 1 LAST PATH I48
J 0
(-850 1350);
DISPLAY 0.978723 (-850 1350);
PAINT WHITE (-850 1350);
DISPLAY INVISIBLE (-850 1350);
FORCEPROP 2 LAST CDS_LIB pure_quanta
J 0
(-900 1200);
PAINT MONO (-900 1200);
DISPLAY INVISIBLE (-900 1200);
FORCEPROP 2 LAST CDS_LOCATION C1203
J 0
(-850 1400);
DISPLAY 1.021277 (-850 1400);
DISPLAY INVISIBLE (-850 1400);
FORCEPROP 2 LAST $SEC 1
J 0
(-850 1400);
DISPLAY 0.680851 (-850 1400);
PAINT MONO (-850 1400);
DISPLAY INVISIBLE (-850 1400);
FORCEPROP 2 LAST CDS_SEC 1
J 0
(-850 1400);
DISPLAY 1.021277 (-850 1400);
DISPLAY INVISIBLE (-850 1400);
FORCEADD Q_CAP..1
(0 1200);
FORCEPROP 1 LAST PART_NUMBER CH6101MEB01
J 0
(50 1050);
DISPLAY 0.638298 (50 1050);
DISPLAY INVISIBLE (50 1050);
FORCEPROP 1 LAST TOLERANCE 20%
J 0
(50 1150);
DISPLAY 0.638298 (50 1150);
FORCEPROP 1 LAST VALUE 10UF
J 0
(50 1250);
DISPLAY 0.638298 (50 1250);
FORCEPROP 1 LAST MATERIAL X6S
J 0
(50 1100);
DISPLAY 0.638298 (50 1100);
FORCEPROP 1 LAST VOLTAGE 6.3V
J 0
(50 1200);
DISPLAY 0.638298 (50 1200);
FORCEPROP 1 LAST PACK_TYPE C0402
J 0
(50 1000);
DISPLAY 0.638298 (50 1000);
FORCEPROP 1 LAST $LOCATION C1231
J 0
(50 1300);
DISPLAY 0.638298 (50 1300);
FORCEPROP 1 LASTPIN (0 1300) $PN 1
J 0
(10 1280);
DISPLAY 0.787234 (10 1280);
FORCEPROP 1 LASTPIN (0 1100) $PN 2
J 0
(10 1080);
DISPLAY 0.787234 (10 1080);
FORCEPROP 1 LAST PATH I49
J 0
(50 1350);
DISPLAY 0.978723 (50 1350);
PAINT WHITE (50 1350);
DISPLAY INVISIBLE (50 1350);
FORCEPROP 2 LAST CDS_LIB pure_quanta
J 0
(0 1200);
PAINT MONO (0 1200);
DISPLAY INVISIBLE (0 1200);
FORCEPROP 2 LAST CDS_LOCATION C1231
J 0
(50 1400);
DISPLAY 1.021277 (50 1400);
DISPLAY INVISIBLE (50 1400);
FORCEPROP 2 LAST $SEC 1
J 0
(50 1400);
DISPLAY 0.680851 (50 1400);
PAINT MONO (50 1400);
DISPLAY INVISIBLE (50 1400);
FORCEPROP 2 LAST CDS_SEC 1
J 0
(50 1400);
DISPLAY 1.021277 (50 1400);
DISPLAY INVISIBLE (50 1400);
FORCEADD UNIVERSAL_GND..1
(-1350 3475);
FORCEPROP 3 LASTPIN (-1350 3525) SIG_NAME GND\g
J 0
(-1340 3535);
DISPLAY 0.659574 (-1340 3535);
PAINT MONO (-1340 3535);
DISPLAY INVISIBLE (-1340 3535);
FORCEPROP 2 LAST ROOM IO_SLOT
J 1
(-1575 3550);
DISPLAY 0.744681 (-1575 3550);
DISPLAY INVISIBLE (-1575 3550);
FORCEPROP 1 LAST PATH I5
J 0
(-1275 3475);
DISPLAY 0.872340 (-1275 3475);
PAINT AQUA (-1275 3475);
DISPLAY INVISIBLE (-1275 3475);
FORCEPROP 1 LAST HDL_POWER GND
J 1
(-1325 3400);
DISPLAY 0.872340 (-1325 3400);
PAINT GREEN (-1325 3400);
DISPLAY INVISIBLE (-1325 3400);
FORCEPROP 2 LAST CDS_LIB logical_power
J 0
(-1350 3475);
PAINT MONO (-1350 3475);
DISPLAY INVISIBLE (-1350 3475);
FORCEADD UNIVERSAL_GND..1
(0 850);
FORCEPROP 3 LASTPIN (0 900) SIG_NAME GND\g
J 0
(10 910);
DISPLAY 0.659574 (10 910);
PAINT MONO (10 910);
DISPLAY INVISIBLE (10 910);
FORCEPROP 2 LAST ROOM IO_SLOT
J 1
(-225 925);
DISPLAY 0.744681 (-225 925);
DISPLAY INVISIBLE (-225 925);
FORCEPROP 1 LAST PATH I50
J 0
(75 850);
DISPLAY 0.872340 (75 850);
PAINT AQUA (75 850);
DISPLAY INVISIBLE (75 850);
FORCEPROP 1 LAST HDL_POWER GND
J 1
(25 775);
DISPLAY 0.872340 (25 775);
PAINT GREEN (25 775);
DISPLAY INVISIBLE (25 775);
FORCEPROP 2 LAST CDS_LIB logical_power
J 0
(0 850);
PAINT MONO (0 850);
DISPLAY INVISIBLE (0 850);
FORCEADD Q_CAP..1
(-2250 475);
FORCEPROP 1 LAST PART_NUMBER CH5222KEB01
J 0
(-2200 325);
DISPLAY 0.638298 (-2200 325);
DISPLAY INVISIBLE (-2200 325);
FORCEPROP 1 LAST VOLTAGE 10V
J 0
(-2200 475);
DISPLAY 0.638298 (-2200 475);
FORCEPROP 1 LAST VALUE 2.2UF
J 0
(-2200 525);
DISPLAY 0.638298 (-2200 525);
FORCEPROP 1 LAST MATERIAL X6S
J 0
(-2200 375);
DISPLAY 0.638298 (-2200 375);
FORCEPROP 1 LAST TOLERANCE 10%
J 0
(-2200 425);
DISPLAY 0.638298 (-2200 425);
FORCEPROP 1 LAST PACK_TYPE C0402
J 0
(-2200 275);
DISPLAY 0.638298 (-2200 275);
FORCEPROP 1 LAST $LOCATION C1183
J 0
(-2200 575);
DISPLAY 0.638298 (-2200 575);
FORCEPROP 1 LASTPIN (-2250 575) $PN 1
J 0
(-2240 555);
DISPLAY 0.787234 (-2240 555);
FORCEPROP 1 LASTPIN (-2250 375) $PN 2
J 0
(-2240 355);
DISPLAY 0.787234 (-2240 355);
FORCEPROP 1 LAST PATH I51
J 0
(-2200 625);
DISPLAY 0.978723 (-2200 625);
PAINT WHITE (-2200 625);
DISPLAY INVISIBLE (-2200 625);
FORCEPROP 2 LAST CDS_LIB pure_quanta
J 0
(-2250 475);
PAINT MONO (-2250 475);
DISPLAY INVISIBLE (-2250 475);
FORCEPROP 2 LAST CDS_LOCATION C1183
J 0
(-2200 675);
DISPLAY 1.021277 (-2200 675);
DISPLAY INVISIBLE (-2200 675);
FORCEPROP 2 LAST $SEC 1
J 0
(-2200 675);
DISPLAY 0.680851 (-2200 675);
PAINT MONO (-2200 675);
DISPLAY INVISIBLE (-2200 675);
FORCEPROP 2 LAST CDS_SEC 1
J 0
(-2200 675);
DISPLAY 1.021277 (-2200 675);
DISPLAY INVISIBLE (-2200 675);
FORCEADD Q_CAP..1
(-1800 475);
FORCEPROP 1 LAST PART_NUMBER CH5222KEB01
J 0
(-1750 325);
DISPLAY 0.638298 (-1750 325);
DISPLAY INVISIBLE (-1750 325);
FORCEPROP 1 LAST MATERIAL X6S
J 0
(-1750 375);
DISPLAY 0.638298 (-1750 375);
FORCEPROP 1 LAST TOLERANCE 10%
J 0
(-1750 425);
DISPLAY 0.638298 (-1750 425);
FORCEPROP 1 LAST VOLTAGE 10V
J 0
(-1750 475);
DISPLAY 0.638298 (-1750 475);
FORCEPROP 1 LAST PACK_TYPE C0402
J 0
(-1750 275);
DISPLAY 0.638298 (-1750 275);
FORCEPROP 1 LAST VALUE 2.2UF
J 0
(-1750 525);
DISPLAY 0.638298 (-1750 525);
FORCEPROP 1 LAST $LOCATION C1189
J 0
(-1750 575);
DISPLAY 0.638298 (-1750 575);
FORCEPROP 1 LASTPIN (-1800 575) $PN 1
J 0
(-1790 555);
DISPLAY 0.787234 (-1790 555);
FORCEPROP 1 LASTPIN (-1800 375) $PN 2
J 0
(-1790 355);
DISPLAY 0.787234 (-1790 355);
FORCEPROP 1 LAST PATH I58
J 0
(-1750 625);
DISPLAY 0.978723 (-1750 625);
PAINT WHITE (-1750 625);
DISPLAY INVISIBLE (-1750 625);
FORCEPROP 2 LAST CDS_LIB pure_quanta
J 0
(-1800 475);
PAINT MONO (-1800 475);
DISPLAY INVISIBLE (-1800 475);
FORCEPROP 2 LAST CDS_LOCATION C1189
J 0
(-1750 675);
DISPLAY 1.021277 (-1750 675);
DISPLAY INVISIBLE (-1750 675);
FORCEPROP 2 LAST $SEC 1
J 0
(-1750 675);
DISPLAY 0.680851 (-1750 675);
PAINT MONO (-1750 675);
DISPLAY INVISIBLE (-1750 675);
FORCEPROP 2 LAST CDS_SEC 1
J 0
(-1750 675);
DISPLAY 1.021277 (-1750 675);
DISPLAY INVISIBLE (-1750 675);
FORCEADD Q_CAP..1
(-1350 475);
FORCEPROP 1 LAST PART_NUMBER CH5222KEB01
J 0
(-1300 325);
DISPLAY 0.638298 (-1300 325);
DISPLAY INVISIBLE (-1300 325);
FORCEPROP 1 LAST MATERIAL X6S
J 0
(-1300 375);
DISPLAY 0.638298 (-1300 375);
FORCEPROP 1 LAST VALUE 2.2UF
J 0
(-1300 525);
DISPLAY 0.638298 (-1300 525);
FORCEPROP 1 LAST VOLTAGE 10V
J 0
(-1300 475);
DISPLAY 0.638298 (-1300 475);
FORCEPROP 1 LAST TOLERANCE 10%
J 0
(-1300 425);
DISPLAY 0.638298 (-1300 425);
FORCEPROP 1 LAST PACK_TYPE C0402
J 0
(-1300 275);
DISPLAY 0.638298 (-1300 275);
FORCEPROP 1 LAST $LOCATION C1200
J 0
(-1300 575);
DISPLAY 0.638298 (-1300 575);
FORCEPROP 1 LASTPIN (-1350 575) $PN 1
J 0
(-1340 555);
DISPLAY 0.787234 (-1340 555);
FORCEPROP 1 LASTPIN (-1350 375) $PN 2
J 0
(-1340 355);
DISPLAY 0.787234 (-1340 355);
FORCEPROP 1 LAST PATH I59
J 0
(-1300 625);
DISPLAY 0.978723 (-1300 625);
PAINT WHITE (-1300 625);
DISPLAY INVISIBLE (-1300 625);
FORCEPROP 2 LAST CDS_LIB pure_quanta
J 0
(-1350 475);
PAINT MONO (-1350 475);
DISPLAY INVISIBLE (-1350 475);
FORCEPROP 2 LAST CDS_LOCATION C1200
J 0
(-1300 675);
DISPLAY 1.021277 (-1300 675);
DISPLAY INVISIBLE (-1300 675);
FORCEPROP 2 LAST $SEC 1
J 0
(-1300 675);
DISPLAY 0.680851 (-1300 675);
PAINT MONO (-1300 675);
DISPLAY INVISIBLE (-1300 675);
FORCEPROP 2 LAST CDS_SEC 1
J 0
(-1300 675);
DISPLAY 1.021277 (-1300 675);
DISPLAY INVISIBLE (-1300 675);
FORCEADD Q_CAP..1
(-2250 3825);
FORCEPROP 1 LAST PART_NUMBER CH622KME901
J 0
(-2200 3675);
DISPLAY 0.638298 (-2200 3675);
DISPLAY INVISIBLE (-2200 3675);
FORCEPROP 1 LAST PACK_TYPE C0603
J 0
(-2200 3625);
DISPLAY 0.638298 (-2200 3625);
FORCEPROP 1 LAST VALUE 22UF
J 0
(-2200 3875);
DISPLAY 0.638298 (-2200 3875);
FORCEPROP 1 LAST VOLTAGE 4V
J 0
(-2200 3825);
DISPLAY 0.638298 (-2200 3825);
FORCEPROP 1 LAST MATERIAL X6S
J 0
(-2200 3725);
DISPLAY 0.638298 (-2200 3725);
FORCEPROP 1 LAST TOLERANCE 20%
J 0
(-2200 3775);
DISPLAY 0.638298 (-2200 3775);
FORCEPROP 1 LAST $LOCATION C1178
J 0
(-2200 3925);
DISPLAY 0.638298 (-2200 3925);
FORCEPROP 1 LASTPIN (-2250 3925) $PN 1
J 0
(-2240 3905);
DISPLAY 0.787234 (-2240 3905);
FORCEPROP 1 LASTPIN (-2250 3725) $PN 2
J 0
(-2240 3705);
DISPLAY 0.787234 (-2240 3705);
FORCEPROP 1 LAST PATH I6
J 0
(-2200 3975);
DISPLAY 0.978723 (-2200 3975);
PAINT WHITE (-2200 3975);
DISPLAY INVISIBLE (-2200 3975);
FORCEPROP 2 LAST CDS_LIB pure_quanta
J 0
(-2250 3825);
PAINT MONO (-2250 3825);
DISPLAY INVISIBLE (-2250 3825);
FORCEPROP 2 LAST CDS_LOCATION C1178
J 0
(-2200 4025);
DISPLAY 1.021277 (-2200 4025);
DISPLAY INVISIBLE (-2200 4025);
FORCEPROP 2 LAST $SEC 1
J 0
(-2200 4025);
DISPLAY 0.680851 (-2200 4025);
PAINT MONO (-2200 4025);
DISPLAY INVISIBLE (-2200 4025);
FORCEPROP 2 LAST CDS_SEC 1
J 0
(-2200 4025);
DISPLAY 1.021277 (-2200 4025);
DISPLAY INVISIBLE (-2200 4025);
FORCEADD Q_CAP..1
(-900 475);
FORCEPROP 1 LAST PART_NUMBER CH5222KEB01
J 0
(-850 325);
DISPLAY 0.638298 (-850 325);
DISPLAY INVISIBLE (-850 325);
FORCEPROP 1 LAST MATERIAL X6S
J 0
(-850 375);
DISPLAY 0.638298 (-850 375);
FORCEPROP 1 LAST PACK_TYPE C0402
J 0
(-850 275);
DISPLAY 0.638298 (-850 275);
FORCEPROP 1 LAST TOLERANCE 10%
J 0
(-850 425);
DISPLAY 0.638298 (-850 425);
FORCEPROP 1 LAST VOLTAGE 10V
J 0
(-850 475);
DISPLAY 0.638298 (-850 475);
FORCEPROP 1 LAST VALUE 2.2UF
J 0
(-850 525);
DISPLAY 0.638298 (-850 525);
FORCEPROP 1 LAST $LOCATION C1204
J 0
(-850 575);
DISPLAY 0.638298 (-850 575);
FORCEPROP 1 LASTPIN (-900 575) $PN 1
J 0
(-890 555);
DISPLAY 0.787234 (-890 555);
FORCEPROP 1 LASTPIN (-900 375) $PN 2
J 0
(-890 355);
DISPLAY 0.787234 (-890 355);
FORCEPROP 1 LAST PATH I60
J 0
(-850 625);
DISPLAY 0.978723 (-850 625);
PAINT WHITE (-850 625);
DISPLAY INVISIBLE (-850 625);
FORCEPROP 2 LAST CDS_LIB pure_quanta
J 0
(-900 475);
PAINT MONO (-900 475);
DISPLAY INVISIBLE (-900 475);
FORCEPROP 2 LAST CDS_LOCATION C1204
J 0
(-850 675);
DISPLAY 1.021277 (-850 675);
DISPLAY INVISIBLE (-850 675);
FORCEPROP 2 LAST $SEC 1
J 0
(-850 675);
DISPLAY 0.680851 (-850 675);
PAINT MONO (-850 675);
DISPLAY INVISIBLE (-850 675);
FORCEPROP 2 LAST CDS_SEC 1
J 0
(-850 675);
DISPLAY 1.021277 (-850 675);
DISPLAY INVISIBLE (-850 675);
FORCEADD Q_CAP..1
(-450 475);
FORCEPROP 1 LAST PART_NUMBER CH5222KEB01
J 0
(-400 325);
DISPLAY 0.638298 (-400 325);
DISPLAY INVISIBLE (-400 325);
FORCEPROP 1 LAST MATERIAL X6S
J 0
(-400 375);
DISPLAY 0.638298 (-400 375);
FORCEPROP 1 LAST VALUE 2.2UF
J 0
(-400 525);
DISPLAY 0.638298 (-400 525);
FORCEPROP 1 LAST VOLTAGE 10V
J 0
(-400 475);
DISPLAY 0.638298 (-400 475);
FORCEPROP 1 LAST TOLERANCE 10%
J 0
(-400 425);
DISPLAY 0.638298 (-400 425);
FORCEPROP 1 LAST PACK_TYPE C0402
J 0
(-400 275);
DISPLAY 0.638298 (-400 275);
FORCEPROP 1 LAST $LOCATION C1214
J 0
(-400 575);
DISPLAY 0.638298 (-400 575);
FORCEPROP 1 LASTPIN (-450 575) $PN 1
J 0
(-440 555);
DISPLAY 0.787234 (-440 555);
FORCEPROP 1 LASTPIN (-450 375) $PN 2
J 0
(-440 355);
DISPLAY 0.787234 (-440 355);
FORCEPROP 1 LAST PATH I61
J 0
(-400 625);
DISPLAY 0.978723 (-400 625);
PAINT WHITE (-400 625);
DISPLAY INVISIBLE (-400 625);
FORCEPROP 2 LAST CDS_LIB pure_quanta
J 0
(-450 475);
PAINT MONO (-450 475);
DISPLAY INVISIBLE (-450 475);
FORCEPROP 2 LAST CDS_LOCATION C1214
J 0
(-400 675);
DISPLAY 1.021277 (-400 675);
DISPLAY INVISIBLE (-400 675);
FORCEPROP 2 LAST $SEC 1
J 0
(-400 675);
DISPLAY 0.680851 (-400 675);
PAINT MONO (-400 675);
DISPLAY INVISIBLE (-400 675);
FORCEPROP 2 LAST CDS_SEC 1
J 0
(-400 675);
DISPLAY 1.021277 (-400 675);
DISPLAY INVISIBLE (-400 675);
FORCEADD Q_CAP..1
(0 475);
FORCEPROP 1 LAST PART_NUMBER CH5222KEB01
J 0
(50 325);
DISPLAY 0.638298 (50 325);
DISPLAY INVISIBLE (50 325);
FORCEPROP 1 LAST MATERIAL X6S
J 0
(50 375);
DISPLAY 0.638298 (50 375);
FORCEPROP 1 LAST VOLTAGE 10V
J 0
(50 475);
DISPLAY 0.638298 (50 475);
FORCEPROP 1 LAST PACK_TYPE C0402
J 0
(50 275);
DISPLAY 0.638298 (50 275);
FORCEPROP 1 LAST VALUE 2.2UF
J 0
(50 525);
DISPLAY 0.638298 (50 525);
FORCEPROP 1 LAST TOLERANCE 10%
J 0
(50 425);
DISPLAY 0.638298 (50 425);
FORCEPROP 1 LAST $LOCATION C1242
J 0
(50 575);
DISPLAY 0.638298 (50 575);
FORCEPROP 1 LASTPIN (0 575) $PN 1
J 0
(10 555);
DISPLAY 0.787234 (10 555);
FORCEPROP 1 LASTPIN (0 375) $PN 2
J 0
(10 355);
DISPLAY 0.787234 (10 355);
FORCEPROP 1 LAST PATH I63
J 0
(50 625);
DISPLAY 0.978723 (50 625);
PAINT WHITE (50 625);
DISPLAY INVISIBLE (50 625);
FORCEPROP 2 LAST CDS_LIB pure_quanta
J 0
(0 475);
PAINT MONO (0 475);
DISPLAY INVISIBLE (0 475);
FORCEPROP 2 LAST CDS_LOCATION C1242
J 0
(50 675);
DISPLAY 1.021277 (50 675);
DISPLAY INVISIBLE (50 675);
FORCEPROP 2 LAST $SEC 1
J 0
(50 675);
DISPLAY 0.680851 (50 675);
PAINT MONO (50 675);
DISPLAY INVISIBLE (50 675);
FORCEPROP 2 LAST CDS_SEC 1
J 0
(50 675);
DISPLAY 1.021277 (50 675);
DISPLAY INVISIBLE (50 675);
FORCEADD UNIVERSAL_GND..1
(0 125);
FORCEPROP 3 LASTPIN (0 175) SIG_NAME GND\g
J 0
(10 185);
DISPLAY 0.659574 (10 185);
PAINT MONO (10 185);
DISPLAY INVISIBLE (10 185);
FORCEPROP 2 LAST ROOM IO_SLOT
J 1
(-225 200);
DISPLAY 0.744681 (-225 200);
DISPLAY INVISIBLE (-225 200);
FORCEPROP 1 LAST PATH I64
J 0
(75 125);
DISPLAY 0.872340 (75 125);
PAINT AQUA (75 125);
DISPLAY INVISIBLE (75 125);
FORCEPROP 1 LAST HDL_POWER GND
J 1
(25 50);
DISPLAY 0.872340 (25 50);
PAINT GREEN (25 50);
DISPLAY INVISIBLE (25 50);
FORCEPROP 2 LAST CDS_LIB logical_power
J 0
(0 125);
PAINT MONO (0 125);
DISPLAY INVISIBLE (0 125);
FORCEADD UNIVERSAL_GND..1
(950 825);
FORCEPROP 3 LASTPIN (950 875) SIG_NAME GND\g
J 0
(960 885);
DISPLAY 0.659574 (960 885);
PAINT MONO (960 885);
DISPLAY INVISIBLE (960 885);
FORCEPROP 2 LAST ROOM IO_SLOT
J 1
(725 900);
DISPLAY 0.744681 (725 900);
DISPLAY INVISIBLE (725 900);
FORCEPROP 1 LAST PATH I68
J 0
(1025 825);
DISPLAY 0.872340 (1025 825);
PAINT AQUA (1025 825);
DISPLAY INVISIBLE (1025 825);
FORCEPROP 1 LAST HDL_POWER GND
J 1
(975 750);
DISPLAY 0.872340 (975 750);
PAINT GREEN (975 750);
DISPLAY INVISIBLE (975 750);
FORCEPROP 2 LAST CDS_LIB logical_power
J 0
(950 825);
PAINT MONO (950 825);
DISPLAY INVISIBLE (950 825);
FORCEADD Q_CAP..1
(-1800 3825);
FORCEPROP 1 LAST PART_NUMBER CH622KME901
J 0
(-1750 3675);
DISPLAY 0.638298 (-1750 3675);
DISPLAY INVISIBLE (-1750 3675);
FORCEPROP 1 LAST PACK_TYPE C0603
J 0
(-1750 3625);
DISPLAY 0.638298 (-1750 3625);
FORCEPROP 1 LAST VALUE 22UF
J 0
(-1750 3875);
DISPLAY 0.638298 (-1750 3875);
FORCEPROP 1 LAST MATERIAL X6S
J 0
(-1750 3725);
DISPLAY 0.638298 (-1750 3725);
FORCEPROP 1 LAST TOLERANCE 20%
J 0
(-1750 3775);
DISPLAY 0.638298 (-1750 3775);
FORCEPROP 1 LAST VOLTAGE 4V
J 0
(-1750 3825);
DISPLAY 0.638298 (-1750 3825);
FORCEPROP 1 LAST $LOCATION C1185
J 0
(-1750 3925);
DISPLAY 0.638298 (-1750 3925);
FORCEPROP 1 LASTPIN (-1800 3925) $PN 1
J 0
(-1790 3905);
DISPLAY 0.787234 (-1790 3905);
FORCEPROP 1 LASTPIN (-1800 3725) $PN 2
J 0
(-1790 3705);
DISPLAY 0.787234 (-1790 3705);
FORCEPROP 1 LAST PATH I7
J 0
(-1750 3975);
DISPLAY 0.978723 (-1750 3975);
PAINT WHITE (-1750 3975);
DISPLAY INVISIBLE (-1750 3975);
FORCEPROP 2 LAST CDS_LIB pure_quanta
J 0
(-1800 3825);
PAINT MONO (-1800 3825);
DISPLAY INVISIBLE (-1800 3825);
FORCEPROP 2 LAST CDS_LOCATION C1185
J 0
(-1750 4025);
DISPLAY 1.021277 (-1750 4025);
DISPLAY INVISIBLE (-1750 4025);
FORCEPROP 2 LAST $SEC 1
J 0
(-1750 4025);
DISPLAY 0.680851 (-1750 4025);
PAINT MONO (-1750 4025);
DISPLAY INVISIBLE (-1750 4025);
FORCEPROP 2 LAST CDS_SEC 1
J 0
(-1750 4025);
DISPLAY 1.021277 (-1750 4025);
DISPLAY INVISIBLE (-1750 4025);
FORCEADD Q_CAP..1
(-850 -725);
FORCEPROP 1 LAST PART_NUMBER CH6101MEB01
J 0
(-800 -875);
DISPLAY 0.638298 (-800 -875);
DISPLAY INVISIBLE (-800 -875);
FORCEPROP 1 LAST PACK_TYPE C0402
J 0
(-800 -925);
DISPLAY 0.638298 (-800 -925);
FORCEPROP 1 LAST VOLTAGE 6.3V
J 0
(-800 -725);
DISPLAY 0.638298 (-800 -725);
FORCEPROP 1 LAST TOLERANCE 20%
J 0
(-800 -775);
DISPLAY 0.638298 (-800 -775);
FORCEPROP 1 LAST MATERIAL X6S
J 0
(-800 -825);
DISPLAY 0.638298 (-800 -825);
FORCEPROP 1 LAST VALUE 10UF
J 0
(-800 -675);
DISPLAY 0.638298 (-800 -675);
FORCEPROP 1 LAST $LOCATION C1206
J 0
(-800 -625);
DISPLAY 0.638298 (-800 -625);
FORCEPROP 1 LASTPIN (-850 -625) $PN 1
J 0
(-840 -645);
DISPLAY 0.787234 (-840 -645);
FORCEPROP 1 LASTPIN (-850 -825) $PN 2
J 0
(-840 -845);
DISPLAY 0.787234 (-840 -845);
FORCEPROP 1 LAST PATH I78
J 0
(-800 -575);
DISPLAY 0.978723 (-800 -575);
PAINT WHITE (-800 -575);
DISPLAY INVISIBLE (-800 -575);
FORCEPROP 2 LAST CDS_LIB pure_quanta
J 0
(-850 -725);
PAINT MONO (-850 -725);
DISPLAY INVISIBLE (-850 -725);
FORCEPROP 2 LAST CDS_LOCATION C1206
J 0
(-800 -525);
DISPLAY 1.021277 (-800 -525);
DISPLAY INVISIBLE (-800 -525);
FORCEPROP 2 LAST $SEC 1
J 0
(-800 -525);
DISPLAY 0.680851 (-800 -525);
PAINT MONO (-800 -525);
DISPLAY INVISIBLE (-800 -525);
FORCEPROP 2 LAST CDS_SEC 1
J 0
(-800 -525);
DISPLAY 1.021277 (-800 -525);
DISPLAY INVISIBLE (-800 -525);
FORCEADD Q_CAP..1
(-1350 3825);
FORCEPROP 1 LAST PART_NUMBER CH622KME901
J 0
(-1300 3675);
DISPLAY 0.638298 (-1300 3675);
DISPLAY INVISIBLE (-1300 3675);
FORCEPROP 1 LAST VOLTAGE 4V
J 0
(-1300 3825);
DISPLAY 0.638298 (-1300 3825);
FORCEPROP 1 LAST VALUE 22UF
J 0
(-1300 3875);
DISPLAY 0.638298 (-1300 3875);
FORCEPROP 1 LAST TOLERANCE 20%
J 0
(-1300 3775);
DISPLAY 0.638298 (-1300 3775);
FORCEPROP 1 LAST MATERIAL X6S
J 0
(-1300 3725);
DISPLAY 0.638298 (-1300 3725);
FORCEPROP 1 LAST PACK_TYPE C0603
J 0
(-1300 3625);
DISPLAY 0.638298 (-1300 3625);
FORCEPROP 1 LAST $LOCATION C1192
J 0
(-1300 3925);
DISPLAY 0.638298 (-1300 3925);
FORCEPROP 1 LASTPIN (-1350 3925) $PN 1
J 0
(-1340 3905);
DISPLAY 0.787234 (-1340 3905);
FORCEPROP 1 LASTPIN (-1350 3725) $PN 2
J 0
(-1340 3705);
DISPLAY 0.787234 (-1340 3705);
FORCEPROP 1 LAST PATH I8
J 0
(-1300 3975);
DISPLAY 0.978723 (-1300 3975);
PAINT WHITE (-1300 3975);
DISPLAY INVISIBLE (-1300 3975);
FORCEPROP 2 LAST CDS_LIB pure_quanta
J 0
(-1350 3825);
PAINT MONO (-1350 3825);
DISPLAY INVISIBLE (-1350 3825);
FORCEPROP 2 LAST CDS_LOCATION C1192
J 0
(-1300 4025);
DISPLAY 1.021277 (-1300 4025);
DISPLAY INVISIBLE (-1300 4025);
FORCEPROP 2 LAST $SEC 1
J 0
(-1300 4025);
DISPLAY 0.680851 (-1300 4025);
PAINT MONO (-1300 4025);
DISPLAY INVISIBLE (-1300 4025);
FORCEPROP 2 LAST CDS_SEC 1
J 0
(-1300 4025);
DISPLAY 1.021277 (-1300 4025);
DISPLAY INVISIBLE (-1300 4025);
FORCEADD Q_CAP..1
(-1350 -725);
FORCEPROP 1 LAST PART_NUMBER CH6221ME900
J 0
(-1300 -875);
DISPLAY 0.638298 (-1300 -875);
DISPLAY INVISIBLE (-1300 -875);
FORCEPROP 1 LAST MATERIAL X6S
J 0
(-1300 -825);
DISPLAY 0.638298 (-1300 -825);
FORCEPROP 1 LAST VALUE 22UF
J 0
(-1300 -675);
DISPLAY 0.638298 (-1300 -675);
FORCEPROP 1 LAST VOLTAGE 6.3V
J 0
(-1300 -725);
DISPLAY 0.638298 (-1300 -725);
FORCEPROP 1 LAST PACK_TYPE C0603
J 0
(-1300 -925);
DISPLAY 0.638298 (-1300 -925);
FORCEPROP 1 LAST TOLERANCE 20%
J 0
(-1300 -775);
DISPLAY 0.638298 (-1300 -775);
FORCEPROP 1 LAST $LOCATION C1201
J 0
(-1300 -625);
DISPLAY 0.638298 (-1300 -625);
FORCEPROP 1 LASTPIN (-1350 -625) $PN 1
J 0
(-1340 -645);
DISPLAY 0.787234 (-1340 -645);
PAINT MONO (-1340 -645);
FORCEPROP 1 LASTPIN (-1350 -825) $PN 2
J 0
(-1340 -845);
DISPLAY 0.787234 (-1340 -845);
PAINT MONO (-1340 -845);
FORCEPROP 1 LAST PATH I87
J 0
(-1300 -575);
DISPLAY 0.978723 (-1300 -575);
PAINT WHITE (-1300 -575);
DISPLAY INVISIBLE (-1300 -575);
FORCEPROP 2 LAST CDS_LIB pure_quanta
J 0
(-1350 -725);
DISPLAY INVISIBLE (-1350 -725);
FORCEPROP 2 LAST CDS_LOCATION C1201
J 0
(-1300 -525);
DISPLAY 1.021277 (-1300 -525);
DISPLAY INVISIBLE (-1300 -525);
FORCEPROP 0 LAST $SEC 1
J 0
(-1300 -575);
DISPLAY 0.680851 (-1300 -575);
PAINT MONO (-1300 -575);
DISPLAY INVISIBLE (-1300 -575);
FORCEPROP 2 LAST CDS_SEC 1
J 0
(-1300 -525);
DISPLAY 1.021277 (-1300 -525);
DISPLAY INVISIBLE (-1300 -525);
FORCEADD UNIVERSAL_GND..1
(-1350 -1075);
FORCEPROP 3 LASTPIN (-1350 -1025) SIG_NAME GND\g
J 0
(-1340 -1015);
DISPLAY 0.659574 (-1340 -1015);
PAINT MONO (-1340 -1015);
DISPLAY INVISIBLE (-1340 -1015);
FORCEPROP 2 LAST ROOM IO_SLOT
J 1
(-1575 -1000);
DISPLAY 0.744681 (-1575 -1000);
DISPLAY INVISIBLE (-1575 -1000);
FORCEPROP 1 LAST PATH I88
J 0
(-1275 -1075);
DISPLAY 0.872340 (-1275 -1075);
PAINT AQUA (-1275 -1075);
DISPLAY INVISIBLE (-1275 -1075);
FORCEPROP 1 LAST HDL_POWER GND
J 1
(-1325 -1150);
DISPLAY 0.872340 (-1325 -1150);
PAINT GREEN (-1325 -1150);
DISPLAY INVISIBLE (-1325 -1150);
FORCEPROP 2 LAST CDS_LIB logical_power
J 0
(-1350 -1075);
PAINT MONO (-1350 -1075);
DISPLAY INVISIBLE (-1350 -1075);
FORCEADD Q_CAP..1
(-1800 -725);
FORCEPROP 1 LAST PART_NUMBER CH6221ME900
J 0
(-1750 -875);
DISPLAY 0.638298 (-1750 -875);
DISPLAY INVISIBLE (-1750 -875);
FORCEPROP 1 LAST PACK_TYPE C0603
J 0
(-1750 -925);
DISPLAY 0.638298 (-1750 -925);
FORCEPROP 1 LAST TOLERANCE 20%
J 0
(-1750 -775);
DISPLAY 0.638298 (-1750 -775);
FORCEPROP 1 LAST VOLTAGE 6.3V
J 0
(-1750 -725);
DISPLAY 0.638298 (-1750 -725);
FORCEPROP 1 LAST VALUE 22UF
J 0
(-1750 -675);
DISPLAY 0.638298 (-1750 -675);
FORCEPROP 1 LAST MATERIAL X6S
J 0
(-1750 -825);
DISPLAY 0.638298 (-1750 -825);
FORCEPROP 1 LAST $LOCATION C1191
J 0
(-1750 -625);
DISPLAY 0.638298 (-1750 -625);
FORCEPROP 1 LASTPIN (-1800 -625) $PN 1
J 0
(-1790 -645);
DISPLAY 0.787234 (-1790 -645);
PAINT MONO (-1790 -645);
FORCEPROP 1 LASTPIN (-1800 -825) $PN 2
J 0
(-1790 -845);
DISPLAY 0.787234 (-1790 -845);
PAINT MONO (-1790 -845);
FORCEPROP 1 LAST PATH I89
J 0
(-1750 -575);
DISPLAY 0.978723 (-1750 -575);
PAINT WHITE (-1750 -575);
DISPLAY INVISIBLE (-1750 -575);
FORCEPROP 2 LAST CDS_LIB pure_quanta
J 0
(-1800 -725);
DISPLAY INVISIBLE (-1800 -725);
FORCEPROP 2 LAST CDS_LOCATION C1191
J 0
(-1750 -525);
DISPLAY 1.021277 (-1750 -525);
DISPLAY INVISIBLE (-1750 -525);
FORCEPROP 0 LAST $SEC 1
J 0
(-1750 -575);
DISPLAY 0.680851 (-1750 -575);
PAINT MONO (-1750 -575);
DISPLAY INVISIBLE (-1750 -575);
FORCEPROP 2 LAST CDS_SEC 1
J 0
(-1750 -525);
DISPLAY 1.021277 (-1750 -525);
DISPLAY INVISIBLE (-1750 -525);
FORCEADD UNIVERSAL_POWER..1
(-2250 -450);
FORCEPROP 3 LASTPIN (-2250 -500) SIG_NAME P3V3_AUX\g
J 0
(-2240 -490);
DISPLAY 0.659574 (-2240 -490);
PAINT MONO (-2240 -490);
DISPLAY INVISIBLE (-2240 -490);
FORCEPROP 1 LAST HDL_POWER P3V3_AUX
J 1
(-2250 -400);
DISPLAY 0.872340 (-2250 -400);
PAINT GREEN (-2250 -400);
FORCEPROP 1 LAST PATH I90
J 0
(-2200 -425);
DISPLAY 0.872340 (-2200 -425);
PAINT AQUA (-2200 -425);
DISPLAY INVISIBLE (-2200 -425);
FORCEPROP 2 LAST CDS_LIB logical_power
J 0
(-2250 -450);
DISPLAY INVISIBLE (-2250 -450);
FORCEADD Q_CAP..1
(-2250 -725);
FORCEPROP 1 LAST PART_NUMBER CH6221ME900
J 0
(-2200 -875);
DISPLAY 0.638298 (-2200 -875);
DISPLAY INVISIBLE (-2200 -875);
FORCEPROP 1 LAST VALUE 22UF
J 0
(-2200 -675);
DISPLAY 0.638298 (-2200 -675);
FORCEPROP 1 LAST VOLTAGE 6.3V
J 0
(-2200 -725);
DISPLAY 0.638298 (-2200 -725);
FORCEPROP 1 LAST TOLERANCE 20%
J 0
(-2200 -775);
DISPLAY 0.638298 (-2200 -775);
FORCEPROP 1 LAST PACK_TYPE C0603
J 0
(-2200 -925);
DISPLAY 0.638298 (-2200 -925);
FORCEPROP 1 LAST MATERIAL X6S
J 0
(-2200 -825);
DISPLAY 0.638298 (-2200 -825);
FORCEPROP 1 LAST $LOCATION C1184
J 0
(-2200 -625);
DISPLAY 0.638298 (-2200 -625);
FORCEPROP 1 LASTPIN (-2250 -625) $PN 1
J 0
(-2240 -645);
DISPLAY 0.787234 (-2240 -645);
PAINT MONO (-2240 -645);
FORCEPROP 1 LASTPIN (-2250 -825) $PN 2
J 0
(-2240 -845);
DISPLAY 0.787234 (-2240 -845);
PAINT MONO (-2240 -845);
FORCEPROP 1 LAST PATH I91
J 0
(-2200 -575);
DISPLAY 0.978723 (-2200 -575);
PAINT WHITE (-2200 -575);
DISPLAY INVISIBLE (-2200 -575);
FORCEPROP 2 LAST CDS_LIB pure_quanta
J 0
(-2250 -725);
DISPLAY INVISIBLE (-2250 -725);
FORCEPROP 2 LAST CDS_LOCATION C1184
J 0
(-2200 -525);
DISPLAY 1.021277 (-2200 -525);
DISPLAY INVISIBLE (-2200 -525);
FORCEPROP 0 LAST $SEC 1
J 0
(-2200 -575);
DISPLAY 0.680851 (-2200 -575);
PAINT MONO (-2200 -575);
DISPLAY INVISIBLE (-2200 -575);
FORCEPROP 2 LAST CDS_SEC 1
J 0
(-2200 -525);
DISPLAY 1.021277 (-2200 -525);
DISPLAY INVISIBLE (-2200 -525);
FORCEADD UNIVERSAL_GND..1
(-850 -1075);
FORCEPROP 3 LASTPIN (-850 -1025) SIG_NAME GND\g
J 0
(-840 -1015);
DISPLAY 0.659574 (-840 -1015);
PAINT MONO (-840 -1015);
DISPLAY INVISIBLE (-840 -1015);
FORCEPROP 2 LAST ROOM IO_SLOT
J 1
(-1075 -1000);
DISPLAY 0.744681 (-1075 -1000);
DISPLAY INVISIBLE (-1075 -1000);
FORCEPROP 1 LAST PATH I92
J 0
(-775 -1075);
DISPLAY 0.872340 (-775 -1075);
PAINT AQUA (-775 -1075);
DISPLAY INVISIBLE (-775 -1075);
FORCEPROP 1 LAST HDL_POWER GND
J 1
(-825 -1150);
DISPLAY 0.872340 (-825 -1150);
PAINT GREEN (-825 -1150);
DISPLAY INVISIBLE (-825 -1150);
FORCEPROP 2 LAST CDS_LIB logical_power
J 0
(-850 -1075);
PAINT MONO (-850 -1075);
DISPLAY INVISIBLE (-850 -1075);
FORCEADD UNIVERSAL_GND..1
(450 -1075);
FORCEPROP 3 LASTPIN (450 -1025) SIG_NAME GND\g
J 0
(460 -1015);
DISPLAY 0.659574 (460 -1015);
PAINT MONO (460 -1015);
DISPLAY INVISIBLE (460 -1015);
FORCEPROP 2 LAST ROOM IO_SLOT
J 1
(225 -1000);
DISPLAY 0.744681 (225 -1000);
DISPLAY INVISIBLE (225 -1000);
FORCEPROP 1 LAST PATH I93
J 0
(525 -1075);
DISPLAY 0.872340 (525 -1075);
PAINT AQUA (525 -1075);
DISPLAY INVISIBLE (525 -1075);
FORCEPROP 1 LAST HDL_POWER GND
J 1
(475 -1150);
DISPLAY 0.872340 (475 -1150);
PAINT GREEN (475 -1150);
DISPLAY INVISIBLE (475 -1150);
FORCEPROP 2 LAST CDS_LIB logical_power
J 0
(450 -1075);
PAINT MONO (450 -1075);
DISPLAY INVISIBLE (450 -1075);
FORCEADD UNIVERSAL_POWER..1
(-850 -450);
FORCEPROP 3 LASTPIN (-850 -500) SIG_NAME P3V3_AUX\g
J 0
(-840 -490);
DISPLAY 0.659574 (-840 -490);
PAINT MONO (-840 -490);
DISPLAY INVISIBLE (-840 -490);
FORCEPROP 1 LAST HDL_POWER P3V3_AUX
J 1
(-850 -400);
DISPLAY 0.872340 (-850 -400);
PAINT GREEN (-850 -400);
FORCEPROP 1 LAST PATH I94
J 0
(-800 -425);
DISPLAY 0.872340 (-800 -425);
PAINT AQUA (-800 -425);
DISPLAY INVISIBLE (-800 -425);
FORCEPROP 2 LAST CDS_LIB logical_power
J 0
(-850 -450);
PAINT MONO (-850 -450);
DISPLAY INVISIBLE (-850 -450);
FORCEADD UNIVERSAL_POWER..1
(0 -450);
FORCEPROP 3 LASTPIN (0 -500) SIG_NAME P3V3_AUX\g
J 0
(10 -490);
DISPLAY 0.659574 (10 -490);
PAINT MONO (10 -490);
DISPLAY INVISIBLE (10 -490);
FORCEPROP 1 LAST HDL_POWER P3V3_AUX
J 1
(0 -400);
DISPLAY 0.872340 (0 -400);
PAINT GREEN (0 -400);
FORCEPROP 1 LAST PATH I95
J 0
(50 -425);
DISPLAY 0.872340 (50 -425);
PAINT AQUA (50 -425);
DISPLAY INVISIBLE (50 -425);
FORCEPROP 2 LAST CDS_LIB logical_power
J 0
(0 -450);
PAINT MONO (0 -450);
DISPLAY INVISIBLE (0 -450);
FORCEADD UNIVERSAL_POWER..1
(4700 2925);
FORCEPROP 3 LASTPIN (4700 2875) SIG_NAME P1V05_PCH_PLL_AUX\g
J 0
(4710 2885);
DISPLAY 0.659574 (4710 2885);
PAINT MONO (4710 2885);
DISPLAY INVISIBLE (4710 2885);
FORCEPROP 1 LAST HDL_POWER P1V05_PCH_PLL_AUX
J 1
(4700 2975);
DISPLAY 0.872340 (4700 2975);
PAINT GREEN (4700 2975);
FORCEPROP 1 LAST PATH I99
J 0
(4750 2950);
DISPLAY 0.872340 (4750 2950);
PAINT AQUA (4750 2950);
DISPLAY INVISIBLE (4750 2950);
FORCEPROP 2 LAST CDS_LIB logical_power
J 0
(4700 2925);
DISPLAY INVISIBLE (4700 2925);
FORCEADD QUANTA_TITLE_BLOCK_C..1
(6400 -1775);
FORCEPROP 0 LAST CDS_CON_LAST_MODIFIED Fri Aug 25 14:03:01 2023
J 0
(4515 -1760);
PAINT MONO (4515 -1760);
DISPLAY INVISIBLE (4515 -1760);
FORCEPROP 2 LAST CUSTOM_TXT_CDS <XR_PAGE_TITLE>
J 0
(-1490 3475);
DISPLAY 0.638298 (-1490 3475);
PAINT PINK (-1490 3475);
DISPLAY INVISIBLE (-1490 3475);
FORCEPROP 2 LAST CUSTOM_TXT_CDS <CON_LAST_MODIFIED>
J 0
(4515 -1760);
DISPLAY 0.978723 (4515 -1760);
FORCEPROP 2 LAST CUSTOM_TXT_CDS <NAME_2>
J 0
(3225 -1725);
FORCEPROP 2 LAST CUSTOM_TXT_CDS <NAME_1>
J 0
(3225 -1600);
FORCEPROP 2 LAST CUSTOM_TXT_CDS <Q_NUMBER>
J 0
(4997 -1672);
DISPLAY 1.212766 (4997 -1672);
FORCEPROP 2 LAST CUSTOM_TXT_CDS <Q_PROJ>
J 0
(4018 -1673);
DISPLAY 1.212766 (4018 -1673);
FORCEPROP 2 LAST CUSTOM_TXT_CDS <Q_REV>
J 0
(6216 -1672);
DISPLAY 1.212766 (6216 -1672);
FORCEPROP 2 LAST CUSTOM_TXT_CDS <CON_PAGE_NUM> OF <CON_TOTAL_PAGES>
J 0
(5954 -1757);
DISPLAY 0.978723 (5954 -1757);
FORCEPROP 1 LAST Q_TITLE EMMITSBURG - DECOUPLING CAPS
J 0
(-2891 -1749);
DISPLAY 2.446809 (-2891 -1749);
PAINT GREEN (-2891 -1749);
FORCEPROP 1 LAST Q_DEPT 
J 1
(2637 -1726);
DISPLAY 1.957447 (2637 -1726);
PAINT GREEN (2637 -1726);
FORCEPROP 2 LAST CDS_XR_PAGE_TITLE CR-189 : @S9S_MB_2U_LIB.S9S_MB_2U(SCH_1):PAGE189
J 0
(-1490 3475);
DISPLAY 0.638298 (-1490 3475);
PAINT PINK (-1490 3475);
DISPLAY INVISIBLE (-1490 3475);
FORCEPROP 2 LAST PAGE_BORDER TRUE
J 0
(-1490 3475);
DISPLAY 0.638298 (-1490 3475);
PAINT PINK (-1490 3475);
DISPLAY INVISIBLE (-1490 3475);
FORCEPROP 1 LAST CDS_LMAN_SYM_OUTLINE -9475,6775,100,-125
J 0
(6400 -1775);
DISPLAY 0.468085 (6400 -1775);
PAINT GREEN (6400 -1775);
DISPLAY INVISIBLE (6400 -1775);
FORCEPROP 2 LAST CDS_LIB pure_quanta
J 0
(6400 -1775);
PAINT MONO (6400 -1775);
DISPLAY INVISIBLE (6400 -1775);
FORCEPROP 1 LAST COMMENT_BODY TRUE
J 0
(6412 -1788);
DISPLAY 0.978723 (6412 -1788);
PAINT GREEN (6412 -1788);
DISPLAY INVISIBLE (6412 -1788);
FORCEADD DNS..2
(2380 3545);
PAINT RED (2380 3545);
FORCEPROP 1 LAST COMMENT_BODY TRUE
J 0
(2380 3545);
DISPLAY INVISIBLE (2380 3545);
FORCEPROP 2 LAST CDS_LIB mstr_misc
J 0
(2380 3545);
PAINT MONO (2380 3545);
DISPLAY INVISIBLE (2380 3545);
FORCEADD DNS..2
(3080 870);
PAINT RED (3080 870);
FORCEPROP 1 LAST COMMENT_BODY TRUE
J 0
(3080 870);
DISPLAY INVISIBLE (3080 870);
FORCEPROP 2 LAST CDS_LIB mstr_misc
J 0
(3080 870);
PAINT MONO (3080 870);
DISPLAY INVISIBLE (3080 870);
FORCEADD DNS..2
(2780 1070);
PAINT RED (2780 1070);
FORCEPROP 1 LAST COMMENT_BODY TRUE
J 0
(2780 1070);
DISPLAY INVISIBLE (2780 1070);
FORCEPROP 2 LAST CDS_LIB mstr_misc
J 0
(2780 1070);
PAINT MONO (2780 1070);
DISPLAY INVISIBLE (2780 1070);
FORCEADD DNS..2
(3955 3545);
PAINT RED (3955 3545);
FORCEPROP 1 LAST COMMENT_BODY TRUE
J 0
(3955 3545);
DISPLAY INVISIBLE (3955 3545);
FORCEPROP 2 LAST CDS_LIB mstr_misc
J 0
(3955 3545);
PAINT MONO (3955 3545);
DISPLAY INVISIBLE (3955 3545);
FORCEADD DNS..2
(2430 870);
PAINT RED (2430 870);
FORCEPROP 1 LAST COMMENT_BODY TRUE
J 0
(2430 870);
DISPLAY INVISIBLE (2430 870);
FORCEPROP 2 LAST CDS_LIB mstr_misc
J 0
(2430 870);
PAINT MONO (2430 870);
DISPLAY INVISIBLE (2430 870);
FORCEADD DNS..2
(3030 3545);
PAINT RED (3030 3545);
FORCEPROP 1 LAST COMMENT_BODY TRUE
J 0
(3030 3545);
DISPLAY INVISIBLE (3030 3545);
FORCEPROP 2 LAST CDS_LIB mstr_misc
J 0
(3030 3545);
PAINT MONO (3030 3545);
DISPLAY INVISIBLE (3030 3545);
FORCEADD DNS..2
(4005 870);
PAINT RED (4005 870);
FORCEPROP 1 LAST COMMENT_BODY TRUE
J 0
(4005 870);
DISPLAY INVISIBLE (4005 870);
FORCEPROP 2 LAST CDS_LIB mstr_misc
J 0
(4005 870);
PAINT MONO (4005 870);
DISPLAY INVISIBLE (4005 870);
FORCEADD DNS..2
(2725 3750);
PAINT RED (2725 3750);
FORCEPROP 1 LAST COMMENT_BODY TRUE
J 0
(2725 3750);
DISPLAY INVISIBLE (2725 3750);
FORCEPROP 2 LAST CDS_LIB mstr_misc
J 0
(2725 3750);
PAINT MONO (2725 3750);
DISPLAY INVISIBLE (2725 3750);
WIRE 16 -1 (3950 4125)(3950 4300);
WIRE 16 -1 (3950 3950)(3950 4125);
WIRE 16 -1 (3250 4125)(3950 4125);
WIRE 16 -1 (2375 4325)(2375 4125);
WIRE 16 -1 (3800 2750)(3800 2875);
WIRE 16 -1 (-850 -625)(-850 -500);
WIRE 16 -1 (4700 100)(4700 225);
WIRE 16 -1 (2375 2825)(2375 2875);
WIRE 16 -1 (2825 2825)(2375 2825);
WIRE 16 -1 (2375 2825)(2375 2750);
WIRE 16 -1 (-850 4000)(-850 4050);
WIRE 16 -1 (-400 4000)(-850 4000);
WIRE 16 -1 (-850 4000)(-850 3925);
WIRE 16 -1 (3800 175)(3800 225);
WIRE 16 -1 (4250 175)(3800 175);
WIRE 16 -1 (3800 100)(3800 175);
WIRE 16 -1 (2425 1375)(2425 1275);
WIRE 16 -1 (4000 1275)(4000 1350);
WIRE 16 -1 (4000 1075)(4000 1275);
WIRE 16 -1 (3300 1275)(4000 1275);
WIRE 16 -1 (-900 1375)(-900 1425);
WIRE 16 -1 (-450 1375)(-900 1375);
WIRE 16 -1 (-900 1375)(-900 1300);
WIRE 16 -1 (-2250 650)(-2250 700);
WIRE 16 -1 (-1800 650)(-2250 650);
WIRE 16 -1 (-2250 650)(-2250 575);
WIRE 16 -1 (-2250 2675)(-2250 2725);
WIRE 16 -1 (-1800 2675)(-2250 2675);
WIRE 16 -1 (-2250 2675)(-2250 2600);
WIRE 16 -1 (-450 2600)(-450 2725);
WIRE 16 -1 (-2250 4000)(-2250 4050);
WIRE 16 -1 (-1800 4000)(-2250 4000);
WIRE 16 -1 (-2250 4000)(-2250 3925);
WIRE 16 -1 (-2250 1375)(-2250 1425);
WIRE 16 -1 (-1800 1375)(-2250 1375);
WIRE 16 -1 (-2250 1375)(-2250 1300);
WIRE 16 -1 (-2250 -550)(-2250 -500);
WIRE 16 -1 (-1800 -550)(-2250 -550);
WIRE 16 -1 (-2250 -550)(-2250 -625);
WIRE 16 -1 (50 4000)(50 4050);
WIRE 16 -1 (500 4000)(50 4000);
WIRE 16 -1 (50 4000)(50 3925);
WIRE 16 -1 (500 1350)(500 1400);
WIRE 16 -1 (950 1350)(500 1350);
WIRE 16 -1 (500 1350)(500 1275);
WIRE 16 -1 (0 -550)(0 -500);
WIRE 16 -1 (450 -550)(0 -550);
WIRE 16 -1 (0 -550)(0 -625);
WIRE 16 -1 (2400 175)(2400 225);
WIRE 16 -1 (2850 175)(2400 175);
WIRE 16 -1 (2400 175)(2400 100);
WIRE 16 -1 (4700 2750)(4700 2875);
WIRE 16 -1 (3275 2425)(3275 2350);
WIRE 16 -1 (3275 2425)(2825 2425);
WIRE 16 -1 (3275 2550)(3275 2425);
WIRE 16 -1 (3800 2350)(3800 2550);
WIRE 16 -1 (4700 2350)(4700 2550);
WIRE 16 -1 (4700 -300)(4700 -100);
WIRE 16 -1 (3300 -225)(3300 -300);
WIRE 16 -1 (3300 -225)(2850 -225);
WIRE 16 -1 (3300 -100)(3300 -225);
WIRE 16 -1 (4250 -225)(4250 -300);
WIRE 16 -1 (4250 -225)(3800 -225);
WIRE 16 -1 (4250 -225)(4250 -100);
WIRE 16 -1 (2375 3350)(2375 3275);
WIRE 16 -1 (3025 3350)(2375 3350);
WIRE 16 -1 (2375 3475)(2375 3350);
WIRE 16 -1 (3950 3275)(3950 3350);
WIRE 16 -1 (-400 3600)(-400 3525);
WIRE 16 -1 (-400 3600)(-850 3600);
WIRE 16 -1 (-400 3600)(-400 3725);
WIRE 16 -1 (4000 600)(4000 675);
WIRE 16 -1 (2425 675)(2425 550);
WIRE 16 -1 (2425 675)(3075 675);
WIRE 16 -1 (2425 800)(2425 675);
WIRE 16 -1 (950 3600)(950 3525);
WIRE 16 -1 (950 3600)(500 3600);
WIRE 16 -1 (950 3725)(950 3600);
WIRE 16 -1 (-900 2275)(-900 2200);
WIRE 16 -1 (-900 2275)(-1350 2275);
WIRE 16 -1 (-900 2400)(-900 2275);
WIRE 16 -1 (-450 2400)(-450 2200);
WIRE 16 -1 (-1350 975)(-1350 900);
WIRE 16 -1 (-1350 975)(-1800 975);
WIRE 16 -1 (-1350 1100)(-1350 975);
WIRE 16 -1 (-1350 3600)(-1350 3525);
WIRE 16 -1 (-1350 3600)(-1800 3600);
WIRE 16 -1 (-1350 3725)(-1350 3600);
WIRE 16 -1 (0 975)(0 900);
WIRE 16 -1 (0 975)(-450 975);
WIRE 16 -1 (0 975)(0 1100);
WIRE 16 -1 (0 250)(0 175);
WIRE 16 -1 (0 250)(-450 250);
WIRE 16 -1 (0 375)(0 250);
WIRE 16 -1 (950 950)(950 875);
WIRE 16 -1 (950 950)(500 950);
WIRE 16 -1 (950 950)(950 1075);
WIRE 16 -1 (-1350 -950)(-1350 -1025);
WIRE 16 -1 (-1350 -950)(-1800 -950);
WIRE 16 -1 (-1350 -825)(-1350 -950);
WIRE 16 -1 (-850 -1025)(-850 -825);
WIRE 16 -1 (450 -950)(450 -1025);
WIRE 16 -1 (450 -950)(0 -950);
WIRE 16 -1 (450 -950)(450 -825);
WIRE 16 2175 (2900 4350)(3500 4350);
WIRE 16 2175 (3500 4350)(3500 4100);
WIRE 16 2175 (2900 4350)(2900 4100);
WIRE 16 2175 (2900 4100)(3500 4100);
WIRE 16 -1 (2800 3750)(3025 3750);
WIRE 16 -1 (3025 3675)(3025 3750);
WIRE 16 -1 (3550 3750)(3025 3750);
WIRE 16 -1 (3550 3750)(3550 3675);
WIRE 16 -1 (3550 3750)(3950 3750);
WIRE 16 -1 (3950 3675)(3950 3750);
WIRE 16 -1 (3950 3750)(3950 3950);
WIRE 16 -1 (3250 3950)(3950 3950);
WIRE 16 -1 (3050 4125)(2375 4125);
WIRE 16 -1 (2375 3950)(3050 3950);
WIRE 16 -1 (2375 4125)(2375 3950);
WIRE 16 -1 (2375 3950)(2375 3750);
WIRE 16 -1 (2375 3750)(2600 3750);
WIRE 16 -1 (2375 3675)(2375 3750);
WIRE 16 -1 (450 -625)(450 -550);
WIRE 16 -1 (0 -950)(0 -825);
WIRE 16 -1 (-1800 -625)(-1800 -550);
WIRE 16 -1 (-1350 -550)(-1800 -550);
WIRE 16 -1 (-1350 -550)(-1350 -625);
WIRE 16 -1 (-2250 -950)(-2250 -825);
WIRE 16 -1 (-1800 -950)(-2250 -950);
WIRE 16 -1 (-1800 -950)(-1800 -825);
WIRE 16 -1 (500 950)(500 1075);
WIRE 16 -1 (-2250 250)(-2250 375);
WIRE 16 -1 (-1800 250)(-2250 250);
WIRE 16 -1 (-1800 250)(-1800 375);
WIRE 16 -1 (-450 375)(-450 250);
WIRE 16 -1 (-900 250)(-900 375);
WIRE 16 -1 (-450 250)(-900 250);
WIRE 16 -1 (-1350 250)(-1800 250);
WIRE 16 -1 (-1350 375)(-1350 250);
WIRE 16 -1 (-1350 250)(-900 250);
WIRE 16 -1 (-450 975)(-450 1100);
WIRE 16 -1 (-450 975)(-900 975);
WIRE 16 -1 (-900 975)(-900 1100);
WIRE 16 -1 (-2250 3600)(-2250 3725);
WIRE 16 -1 (-1800 3600)(-2250 3600);
WIRE 16 -1 (-1800 3600)(-1800 3725);
WIRE 16 -1 (-2250 975)(-2250 1100);
WIRE 16 -1 (-1800 975)(-2250 975);
WIRE 16 -1 (-1800 975)(-1800 1100);
WIRE 16 -1 (-1800 1300)(-1800 1375);
WIRE 16 -1 (-1350 1375)(-1800 1375);
WIRE 16 -1 (-1350 1375)(-1350 1300);
WIRE 16 -1 (-1800 3925)(-1800 4000);
WIRE 16 -1 (-1350 4000)(-1800 4000);
WIRE 16 -1 (-1350 4000)(-1350 3925);
WIRE 16 -1 (-2250 2275)(-2250 2400);
WIRE 16 -1 (-1800 2275)(-2250 2275);
WIRE 16 -1 (-1800 2275)(-1800 2400);
WIRE 16 -1 (-1350 2275)(-1800 2275);
WIRE 16 -1 (-1350 2400)(-1350 2275);
WIRE 16 -1 (-1800 2600)(-1800 2675);
WIRE 16 -1 (-1350 2675)(-1800 2675);
WIRE 16 -1 (-1350 2675)(-1350 2600);
WIRE 16 -1 (-900 2675)(-1350 2675);
WIRE 16 -1 (-900 2675)(-900 2600);
WIRE 16 -1 (500 3925)(500 4000);
WIRE 16 -1 (950 4000)(500 4000);
WIRE 16 -1 (950 4000)(950 3925);
WIRE 16 -1 (50 3600)(50 3725);
WIRE 16 -1 (500 3600)(50 3600);
WIRE 16 -1 (500 3600)(500 3725);
WIRE 16 -1 (-1800 575)(-1800 650);
WIRE 16 -1 (-1350 650)(-1800 650);
WIRE 16 -1 (-1350 650)(-1350 575);
WIRE 16 -1 (-1350 650)(-900 650);
WIRE 16 -1 (-900 650)(-900 575);
WIRE 16 -1 (-450 650)(-900 650);
WIRE 16 -1 (-450 650)(-450 575);
WIRE 16 -1 (0 650)(-450 650);
WIRE 16 -1 (0 650)(0 575);
WIRE 16 -1 (950 1275)(950 1350);
WIRE 16 -1 (-450 1300)(-450 1375);
WIRE 16 -1 (0 1375)(-450 1375);
WIRE 16 -1 (0 1300)(0 1375);
WIRE 16 -1 (3075 800)(3075 675);
WIRE 16 -1 (3600 800)(3600 675);
WIRE 16 -1 (3600 675)(4000 675);
WIRE 16 -1 (4000 675)(4000 800);
WIRE 16 -1 (-850 3600)(-850 3725);
WIRE 16 -1 (4000 1000)(4000 1075);
WIRE 16 -1 (3600 1075)(3600 1000);
WIRE 16 -1 (3600 1075)(4000 1075);
WIRE 16 -1 (3075 1000)(3075 1075);
WIRE 16 -1 (3600 1075)(3075 1075);
WIRE 16 -1 (2850 1075)(3075 1075);
WIRE 16 -1 (2425 1275)(3100 1275);
WIRE 16 -1 (2425 1275)(2425 1075);
WIRE 16 -1 (2425 1075)(2650 1075);
WIRE 16 -1 (2425 1000)(2425 1075);
WIRE 16 -1 (3550 3475)(3550 3350);
WIRE 16 -1 (3550 3350)(3950 3350);
WIRE 16 -1 (3950 3350)(3950 3475);
WIRE 16 -1 (3025 3475)(3025 3350);
WIRE 16 -1 (3800 -225)(3800 -100);
WIRE 16 -1 (2850 100)(2850 175);
WIRE 16 -1 (3300 175)(2850 175);
WIRE 16 -1 (3300 175)(3300 100);
WIRE 16 -1 (2400 -225)(2400 -100);
WIRE 16 -1 (2850 -225)(2400 -225);
WIRE 16 -1 (2850 -225)(2850 -100);
WIRE 16 -1 (4250 100)(4250 175);
WIRE 16 -1 (-400 3925)(-400 4000);
WIRE 16 -1 (2825 2750)(2825 2825);
WIRE 16 -1 (3275 2825)(2825 2825);
WIRE 16 -1 (3275 2825)(3275 2750);
WIRE 16 -1 (2375 2425)(2375 2550);
WIRE 16 -1 (2825 2425)(2375 2425);
WIRE 16 -1 (2825 2425)(2825 2550);
WIRE 16 2175 (1575 4450)(1575 -1250);
DOT 1 (450 -950);
DOT 1 (-1350 -950);
DOT 1 (-1800 -950);
DOT 1 (-450 975);
DOT 1 (-1800 250);
DOT 1 (3950 3350);
DOT 1 (4000 675);
DOT 1 (2425 675);
DOT 1 (4000 1075);
DOT 1 (2425 1275);
DOT 1 (3800 175);
DOT 1 (-450 250);
DOT 1 (-900 650);
DOT 1 (-1800 650);
DOT 1 (-1800 1375);
DOT 1 (-1800 975);
DOT 1 (-900 250);
DOT 1 (3300 -225);
DOT 1 (-1350 2275);
DOT 1 (-450 650);
DOT 1 (0 975);
DOT 1 (-2250 4000);
DOT 1 (-1800 3600);
DOT 1 (-1800 4000);
DOT 1 (-1350 3600);
DOT 1 (-850 4000);
DOT 1 (-400 3600);
DOT 1 (950 3600);
DOT 1 (-2250 650);
DOT 1 (-1350 250);
DOT 1 (-1350 650);
DOT 1 (0 250);
DOT 1 (-2250 -550);
DOT 1 (-1800 -550);
DOT 1 (0 -550);
DOT 1 (-2250 1375);
DOT 1 (-1350 975);
DOT 1 (-900 2275);
DOT 1 (-1350 2675);
DOT 1 (-1800 2675);
DOT 1 (-1800 2275);
DOT 1 (-2250 2675);
DOT 1 (500 3600);
DOT 1 (500 4000);
DOT 1 (4000 1275);
DOT 1 (2425 1075);
DOT 1 (2850 175);
DOT 1 (2400 175);
DOT 1 (4250 -225);
DOT 1 (2850 -225);
DOT 1 (950 950);
DOT 1 (3600 1075);
DOT 1 (3075 1075);
DOT 1 (3275 2425);
DOT 1 (2825 2825);
DOT 1 (2825 2425);
DOT 1 (2375 2825);
DOT 1 (3950 3950);
DOT 1 (-450 1375);
DOT 1 (-900 1375);
DOT 1 (50 4000);
DOT 1 (500 1350);
DOT 1 (2375 3750);
DOT 1 (2375 3950);
DOT 1 (3025 3750);
DOT 1 (3950 3750);
DOT 1 (2375 3350);
DOT 1 (3550 3750);
DOT 1 (2375 4125);
DOT 1 (3950 4125);
FORCENOTE
20220815 ADD R4803
(2875 4375) 0;
DISPLAY LEFT (2875 4375);
DISPLAY 0.808511 (2875 4375);
PAINT PINK (2875 4375);
FORCENOTE
P1V05_PCH_PLL_AUX DECOUPLING CAPS
(2375 4625) 0;
DISPLAY LEFT (2375 4625);
DISPLAY 2.000000 (2375 4625);
PAINT YELLOW (2375 4625);
FORCENOTE
P1V05_PCH_AUX DECOUPLING CAPS
(-2250 4350) 0;
DISPLAY LEFT (-2250 4350);
DISPLAY 2.000000 (-2250 4350);
PAINT YELLOW (-2250 4350);
FORCENOTE
P1V05_PCH_AUX DECOUPLING CAPS
(-2250 1750) 0;
DISPLAY LEFT (-2250 1750);
DISPLAY 2.000000 (-2250 1750);
PAINT YELLOW (-2250 1750);
FORCENOTE
P3V3_AUX DECOUPLING CAPS
(-2250 -225) 0;
DISPLAY LEFT (-2250 -225);
DISPLAY 2.000000 (-2250 -225);
PAINT YELLOW (-2250 -225);
FORCENOTE
P1V8_PCH_AUX DECOUPLING CAPS
(-2250 3025) 0;
DISPLAY LEFT (-2250 3025);
DISPLAY 2.000000 (-2250 3025);
PAINT YELLOW (-2250 3025);
FORCENOTE
P1V8_PCH_PLL_AUX DECOUPLING CAPS
(2450 1725) 0;
DISPLAY LEFT (2450 1725);
DISPLAY 2.000000 (2450 1725);
PAINT YELLOW (2450 1725);
QUIT
